G04 ================== begin FILE IDENTIFICATION RECORD ==================*
G04 Layout Name:  D:/<user>/Wistron_project/16342-2/gbr/16342-2.brd*
G04 Film Name:    L1*
G04 File Format:  Gerber RS274X*
G04 File Origin:  Cadence Allegro 16.5-S056*
G04 Origin Date:  Mon Aug 07 11:24:35 2017*
G04 *
G04 Layer:  VIA CLASS/TOP*
G04 Layer:  PIN/TOP*
G04 Layer:  ETCH/TOP*
G04 Layer:  DRAWING FORMAT/LAYER_PCB_STORY*
G04 Layer:  DRAWING FORMAT/LAYER_L1*
G04 *
G04 Offset:    (0.00 0.00)*
G04 Mirror:    No*
G04 Mode:      Positive*
G04 Rotation:  0*
G04 FullContactRelief:  No*
G04 UndefLineWidth:     6.00*
G04 ================== end FILE IDENTIFICATION RECORD ====================*
%FSLAX35Y35*MOIN*%
%IR0*IPPOS*OFA0.00000B0.00000*MIA0B0*SFA1.00000B1.00000*%
%AMMACRO57*
4,1,40,.013,.017,
-.013,.017,
-.013695,.016939,
-.014368,.016759,
-.015,.016464,
-.015571,.016064,
-.016064,.015571,
-.016464,.015,
-.016759,.014368,
-.016939,.013695,
-.017,.013,
-.017,-.013,
-.016939,-.013695,
-.016759,-.014368,
-.016464,-.015,
-.016064,-.015571,
-.015571,-.016064,
-.015,-.016464,
-.014368,-.016759,
-.013695,-.016939,
-.013,-.017,
.013,-.017,
.013695,-.016939,
.014368,-.016759,
.015,-.016464,
.015571,-.016064,
.016064,-.015571,
.016464,-.015,
.016759,-.014368,
.016939,-.013695,
.017,-.013,
.017,.013,
.016939,.013695,
.016759,.014368,
.016464,.015,
.016064,.015571,
.015571,.016064,
.015,.016464,
.014368,.016759,
.013695,.016939,
.013,.017,
0.0*
%
%ADD57MACRO57*%
%AMMACRO15*
4,1,40,.017,-.013,
.017,.013,
.016939,.013695,
.016759,.014368,
.016464,.015,
.016064,.015571,
.015571,.016064,
.015,.016464,
.014368,.016759,
.013695,.016939,
.013,.017,
-.013,.017,
-.013695,.016939,
-.014368,.016759,
-.015,.016464,
-.015571,.016064,
-.016064,.015571,
-.016464,.015,
-.016759,.014368,
-.016939,.013695,
-.017,.013,
-.017,-.013,
-.016939,-.013695,
-.016759,-.014368,
-.016464,-.015,
-.016064,-.015571,
-.015571,-.016064,
-.015,-.016464,
-.014368,-.016759,
-.013695,-.016939,
-.013,-.017,
.013,-.017,
.013695,-.016939,
.014368,-.016759,
.015,-.016464,
.015571,-.016064,
.016064,-.015571,
.016464,-.015,
.016759,-.014368,
.016939,-.013695,
.017,-.013,
0.0*
%
%ADD15MACRO15*%
%AMMACRO86*
4,1,40,.008,.009,
.008695,.008939,
.009368,.008759,
.01,.008464,
.010571,.008064,
.011064,.007571,
.011464,.007,
.011759,.006368,
.011939,.005695,
.012,.005,
.012,-.005,
.011939,-.005695,
.011759,-.006368,
.011464,-.007,
.011064,-.007571,
.010571,-.008064,
.01,-.008464,
.009368,-.008759,
.008695,-.008939,
.008,-.009,
-.008,-.009,
-.008695,-.008939,
-.009368,-.008759,
-.01,-.008464,
-.010571,-.008064,
-.011064,-.007571,
-.011464,-.007,
-.011759,-.006368,
-.011939,-.005695,
-.012,-.005,
-.012,.005,
-.011939,.005695,
-.011759,.006368,
-.011464,.007,
-.011064,.007571,
-.010571,.008064,
-.01,.008464,
-.009368,.008759,
-.008695,.008939,
-.008,.009,
.008,.009,
0.0*
%
%ADD86MACRO86*%
%AMMACRO97*
4,1,40,.019,.017,
-.019,.017,
-.019695,.016939,
-.020368,.016759,
-.021,.016464,
-.021571,.016064,
-.022064,.015571,
-.022464,.015,
-.022759,.014368,
-.022939,.013695,
-.023,.013,
-.023,-.013,
-.022939,-.013695,
-.022759,-.014368,
-.022464,-.015,
-.022064,-.015571,
-.021571,-.016064,
-.021,-.016464,
-.020368,-.016759,
-.019695,-.016939,
-.019,-.017,
.019,-.017,
.019695,-.016939,
.020368,-.016759,
.021,-.016464,
.021571,-.016064,
.022064,-.015571,
.022464,-.015,
.022759,-.014368,
.022939,-.013695,
.023,-.013,
.023,.013,
.022939,.013695,
.022759,.014368,
.022464,.015,
.022064,.015571,
.021571,.016064,
.021,.016464,
.020368,.016759,
.019695,.016939,
.019,.017,
0.0*
%
%ADD97MACRO97*%
%ADD72O,.06X.111*%
%AMMACRO68*
4,1,15,-.0275,-.115,
-.0275,.02323,
-.02431,.026923,
-.021809,.031114,
-.020074,.035675,
-.019157,.040469,
-.019087,.045348,
-.019865,.050166,
-.021468,.054776,
-.023847,.059037,
-.02693,.06282,
-.0275,.06339,
-.0275,.115,
.0275,.115,
.0275,-.115,
-.0275,-.115,
0.0*
%
%ADD68MACRO68*%
%ADD114R,.01X.007*%
%ADD22C,.01*%
%ADD20C,.02*%
%ADD87C,.03*%
%ADD36C,.022*%
%ADD21C,.04*%
%ADD120C,.05*%
%ADD119C,.032*%
%ADD27C,.014*%
%ADD71C,.042*%
%ADD116R,.047X.108*%
%ADD54C,.016*%
%ADD28C,.026*%
%ADD55C,.018*%
%ADD19C,.028*%
%ADD16C,.056*%
%AMMACRO67*
4,1,40,.0225,-.007,
.022378,-.008389,
.022018,-.009736,
.021428,-.011,
.020628,-.012142,
.019642,-.013128,
.0185,-.013928,
.017236,-.014518,
.015889,-.014878,
.0145,-.015,
-.0145,-.015,
-.015889,-.014878,
-.017236,-.014518,
-.0185,-.013928,
-.019642,-.013128,
-.020628,-.012142,
-.021428,-.011,
-.022018,-.009736,
-.022378,-.008389,
-.0225,-.007,
-.0225,.007,
-.022378,.008389,
-.022018,.009736,
-.021428,.011,
-.020628,.012142,
-.019642,.013128,
-.0185,.013928,
-.017236,.014518,
-.015889,.014878,
-.0145,.015,
.0145,.015,
.015889,.014878,
.017236,.014518,
.0185,.013928,
.019642,.013128,
.020628,.012142,
.021428,.011,
.022018,.009736,
.022378,.008389,
.0225,.007,
.0225,-.007,
0.0*
%
%ADD67MACRO67*%
%AMMACRO85*
4,1,40,-.007,-.0225,
-.008389,-.022378,
-.009736,-.022018,
-.011,-.021428,
-.012142,-.020628,
-.013128,-.019642,
-.013928,-.0185,
-.014518,-.017236,
-.014878,-.015889,
-.015,-.0145,
-.015,.0145,
-.014878,.015889,
-.014518,.017236,
-.013928,.0185,
-.013128,.019642,
-.012142,.020628,
-.011,.021428,
-.009736,.022018,
-.008389,.022378,
-.007,.0225,
.007,.0225,
.008389,.022378,
.009736,.022018,
.011,.021428,
.012142,.020628,
.013128,.019642,
.013928,.0185,
.014518,.017236,
.014878,.015889,
.015,.0145,
.015,-.0145,
.014878,-.015889,
.014518,-.017236,
.013928,-.0185,
.013128,-.019642,
.012142,-.020628,
.011,-.021428,
.009736,-.022018,
.008389,-.022378,
.007,-.0225,
-.007,-.0225,
0.0*
%
%ADD85MACRO85*%
%AMMACRO37*
4,1,40,.011,-.007,
.011,.007,
.010939,.007695,
.010759,.008368,
.010464,.009,
.010064,.009571,
.009571,.010064,
.009,.010464,
.008368,.010759,
.007695,.010939,
.007,.011,
-.007,.011,
-.007695,.010939,
-.008368,.010759,
-.009,.010464,
-.009571,.010064,
-.010064,.009571,
-.010464,.009,
-.010759,.008368,
-.010939,.007695,
-.011,.007,
-.011,-.007,
-.010939,-.007695,
-.010759,-.008368,
-.010464,-.009,
-.010064,-.009571,
-.009571,-.010064,
-.009,-.010464,
-.008368,-.010759,
-.007695,-.010939,
-.007,-.011,
.007,-.011,
.007695,-.010939,
.008368,-.010759,
.009,-.010464,
.009571,-.010064,
.010064,-.009571,
.010464,-.009,
.010759,-.008368,
.010939,-.007695,
.011,-.007,
0.0*
%
%ADD37MACRO37*%
%AMMACRO12*
4,1,40,.007,.011,
-.007,.011,
-.007695,.010939,
-.008368,.010759,
-.009,.010464,
-.009571,.010064,
-.010064,.009571,
-.010464,.009,
-.010759,.008368,
-.010939,.007695,
-.011,.007,
-.011,-.007,
-.010939,-.007695,
-.010759,-.008368,
-.010464,-.009,
-.010064,-.009571,
-.009571,-.010064,
-.009,-.010464,
-.008368,-.010759,
-.007695,-.010939,
-.007,-.011,
.007,-.011,
.007695,-.010939,
.008368,-.010759,
.009,-.010464,
.009571,-.010064,
.010064,-.009571,
.010464,-.009,
.010759,-.008368,
.010939,-.007695,
.011,-.007,
.011,.007,
.010939,.007695,
.010759,.008368,
.010464,.009,
.010064,.009571,
.009571,.010064,
.009,.010464,
.008368,.010759,
.007695,.010939,
.007,.011,
0.0*
%
%ADD12MACRO12*%
%ADD108R,.066X.066*%
%AMMACRO30*
4,1,40,-.012,.008,
-.012,-.008,
-.011939,-.008695,
-.011759,-.009368,
-.011464,-.01,
-.011064,-.010571,
-.010571,-.011064,
-.01,-.011464,
-.009368,-.011759,
-.008695,-.011939,
-.008,-.012,
.008,-.012,
.008695,-.011939,
.009368,-.011759,
.01,-.011464,
.010571,-.011064,
.011064,-.010571,
.011464,-.01,
.011759,-.009368,
.011939,-.008695,
.012,-.008,
.012,.008,
.011939,.008695,
.011759,.009368,
.011464,.01,
.011064,.010571,
.010571,.011064,
.01,.011464,
.009368,.011759,
.008695,.011939,
.008,.012,
-.008,.012,
-.008695,.011939,
-.009368,.011759,
-.01,.011464,
-.010571,.011064,
-.011064,.010571,
-.011464,.01,
-.011759,.009368,
-.011939,.008695,
-.012,.008,
0.0*
%
%ADD30MACRO30*%
%AMMACRO42*
4,1,40,.008,.012,
-.008,.012,
-.008695,.011939,
-.009368,.011759,
-.01,.011464,
-.010571,.011064,
-.011064,.010571,
-.011464,.01,
-.011759,.009368,
-.011939,.008695,
-.012,.008,
-.012,-.008,
-.011939,-.008695,
-.011759,-.009368,
-.011464,-.01,
-.011064,-.010571,
-.010571,-.011064,
-.01,-.011464,
-.009368,-.011759,
-.008695,-.011939,
-.008,-.012,
.008,-.012,
.008695,-.011939,
.009368,-.011759,
.01,-.011464,
.010571,-.011064,
.011064,-.010571,
.011464,-.01,
.011759,-.009368,
.011939,-.008695,
.012,-.008,
.012,.008,
.011939,.008695,
.011759,.009368,
.011464,.01,
.011064,.010571,
.010571,.011064,
.01,.011464,
.009368,.011759,
.008695,.011939,
.008,.012,
0.0*
%
%ADD42MACRO42*%
%AMMACRO123*
4,1,6,.0135,-.025,
-.0065,-.005,
-.0135,-.005,
-.0135,.005,
-.0065,.005,
.0135,.025,
.0135,-.025,
0.0*
%
%ADD123MACRO123*%
%AMMACRO64*
4,1,40,-.013,-.017,
.013,-.017,
.013695,-.016939,
.014368,-.016759,
.015,-.016464,
.015571,-.016064,
.016064,-.015571,
.016464,-.015,
.016759,-.014368,
.016939,-.013695,
.017,-.013,
.017,.013,
.016939,.013695,
.016759,.014368,
.016464,.015,
.016064,.015571,
.015571,.016064,
.015,.016464,
.014368,.016759,
.013695,.016939,
.013,.017,
-.013,.017,
-.013695,.016939,
-.014368,.016759,
-.015,.016464,
-.015571,.016064,
-.016064,.015571,
-.016464,.015,
-.016759,.014368,
-.016939,.013695,
-.017,.013,
-.017,-.013,
-.016939,-.013695,
-.016759,-.014368,
-.016464,-.015,
-.016064,-.015571,
-.015571,-.016064,
-.015,-.016464,
-.014368,-.016759,
-.013695,-.016939,
-.013,-.017,
0.0*
%
%ADD64MACRO64*%
%AMMACRO112*
4,1,6,-.025,-.0135,
-.005,.0065,
-.005,.0135,
.005,.0135,
.005,.0065,
.025,-.0135,
-.025,-.0135,
0.0*
%
%ADD112MACRO112*%
%AMMACRO76*
4,1,40,-.009,.008,
-.008939,.008695,
-.008759,.009368,
-.008464,.01,
-.008064,.010571,
-.007571,.011064,
-.007,.011464,
-.006368,.011759,
-.005695,.011939,
-.005,.012,
.005,.012,
.005695,.011939,
.006368,.011759,
.007,.011464,
.007571,.011064,
.008064,.010571,
.008464,.01,
.008759,.009368,
.008939,.008695,
.009,.008,
.009,-.008,
.008939,-.008695,
.008759,-.009368,
.008464,-.01,
.008064,-.010571,
.007571,-.011064,
.007,-.011464,
.006368,-.011759,
.005695,-.011939,
.005,-.012,
-.005,-.012,
-.005695,-.011939,
-.006368,-.011759,
-.007,-.011464,
-.007571,-.011064,
-.008064,-.010571,
-.008464,-.01,
-.008759,-.009368,
-.008939,-.008695,
-.009,-.008,
-.009,.008,
0.0*
%
%ADD76MACRO76*%
%AMMACRO46*
4,1,40,-.017,.013,
-.017,-.013,
-.016939,-.013695,
-.016759,-.014368,
-.016464,-.015,
-.016064,-.015571,
-.015571,-.016064,
-.015,-.016464,
-.014368,-.016759,
-.013695,-.016939,
-.013,-.017,
.013,-.017,
.013695,-.016939,
.014368,-.016759,
.015,-.016464,
.015571,-.016064,
.016064,-.015571,
.016464,-.015,
.016759,-.014368,
.016939,-.013695,
.017,-.013,
.017,.013,
.016939,.013695,
.016759,.014368,
.016464,.015,
.016064,.015571,
.015571,.016064,
.015,.016464,
.014368,.016759,
.013695,.016939,
.013,.017,
-.013,.017,
-.013695,.016939,
-.014368,.016759,
-.015,.016464,
-.015571,.016064,
-.016064,.015571,
-.016464,.015,
-.016759,.014368,
-.016939,.013695,
-.017,.013,
0.0*
%
%ADD46MACRO46*%
%AMMACRO90*
4,1,40,.008,.009,
.008695,.008939,
.009368,.008759,
.01,.008464,
.010571,.008064,
.011064,.007571,
.011464,.007,
.011759,.006368,
.011939,.005695,
.012,.005,
.012,-.005,
.011939,-.005695,
.011759,-.006368,
.011464,-.007,
.011064,-.007571,
.010571,-.008064,
.01,-.008464,
.009368,-.008759,
.008695,-.008939,
.008,-.009,
-.008,-.009,
-.008695,-.008939,
-.009368,-.008759,
-.01,-.008464,
-.010571,-.008064,
-.011064,-.007571,
-.011464,-.007,
-.011759,-.006368,
-.011939,-.005695,
-.012,-.005,
-.012,.005,
-.011939,.005695,
-.011759,.006368,
-.011464,.007,
-.011064,.007571,
-.010571,.008064,
-.01,.008464,
-.009368,.008759,
-.008695,.008939,
-.008,.009,
.008,.009,
0.0*
%
%ADD90MACRO90*%
%AMMACRO52*
4,1,6,.005,.0135,
.005,.0065,
.025,-.0135,
-.025,-.0135,
-.005,.0065,
-.005,.0135,
.005,.0135,
0.0*
%
%ADD52MACRO52*%
%AMMACRO38*
4,1,40,.011,-.007,
.011,.007,
.010939,.007695,
.010759,.008368,
.010464,.009,
.010064,.009571,
.009571,.010064,
.009,.010464,
.008368,.010759,
.007695,.010939,
.007,.011,
-.007,.011,
-.007695,.010939,
-.008368,.010759,
-.009,.010464,
-.009571,.010064,
-.010064,.009571,
-.010464,.009,
-.010759,.008368,
-.010939,.007695,
-.011,.007,
-.011,-.007,
-.010939,-.007695,
-.010759,-.008368,
-.010464,-.009,
-.010064,-.009571,
-.009571,-.010064,
-.009,-.010464,
-.008368,-.010759,
-.007695,-.010939,
-.007,-.011,
.007,-.011,
.007695,-.010939,
.008368,-.010759,
.009,-.010464,
.009571,-.010064,
.010064,-.009571,
.010464,-.009,
.010759,-.008368,
.010939,-.007695,
.011,-.007,
0.0*
%
%ADD38MACRO38*%
%AMMACRO13*
4,1,40,.007,.011,
-.007,.011,
-.007695,.010939,
-.008368,.010759,
-.009,.010464,
-.009571,.010064,
-.010064,.009571,
-.010464,.009,
-.010759,.008368,
-.010939,.007695,
-.011,.007,
-.011,-.007,
-.010939,-.007695,
-.010759,-.008368,
-.010464,-.009,
-.010064,-.009571,
-.009571,-.010064,
-.009,-.010464,
-.008368,-.010759,
-.007695,-.010939,
-.007,-.011,
.007,-.011,
.007695,-.010939,
.008368,-.010759,
.009,-.010464,
.009571,-.010064,
.010064,-.009571,
.010464,-.009,
.010759,-.008368,
.010939,-.007695,
.011,-.007,
.011,.007,
.010939,.007695,
.010759,.008368,
.010464,.009,
.010064,.009571,
.009571,.010064,
.009,.010464,
.008368,.010759,
.007695,.010939,
.007,.011,
0.0*
%
%ADD13MACRO13*%
%AMMACRO29*
4,1,40,-.012,.008,
-.012,-.008,
-.011939,-.008695,
-.011759,-.009368,
-.011464,-.01,
-.011064,-.010571,
-.010571,-.011064,
-.01,-.011464,
-.009368,-.011759,
-.008695,-.011939,
-.008,-.012,
.008,-.012,
.008695,-.011939,
.009368,-.011759,
.01,-.011464,
.010571,-.011064,
.011064,-.010571,
.011464,-.01,
.011759,-.009368,
.011939,-.008695,
.012,-.008,
.012,.008,
.011939,.008695,
.011759,.009368,
.011464,.01,
.011064,.010571,
.010571,.011064,
.01,.011464,
.009368,.011759,
.008695,.011939,
.008,.012,
-.008,.012,
-.008695,.011939,
-.009368,.011759,
-.01,.011464,
-.010571,.011064,
-.011064,.010571,
-.011464,.01,
-.011759,.009368,
-.011939,.008695,
-.012,.008,
0.0*
%
%ADD29MACRO29*%
%AMMACRO41*
4,1,40,.008,.012,
-.008,.012,
-.008695,.011939,
-.009368,.011759,
-.01,.011464,
-.010571,.011064,
-.011064,.010571,
-.011464,.01,
-.011759,.009368,
-.011939,.008695,
-.012,.008,
-.012,-.008,
-.011939,-.008695,
-.011759,-.009368,
-.011464,-.01,
-.011064,-.010571,
-.010571,-.011064,
-.01,-.011464,
-.009368,-.011759,
-.008695,-.011939,
-.008,-.012,
.008,-.012,
.008695,-.011939,
.009368,-.011759,
.01,-.011464,
.010571,-.011064,
.011064,-.010571,
.011464,-.01,
.011759,-.009368,
.011939,-.008695,
.012,-.008,
.012,.008,
.011939,.008695,
.011759,.009368,
.011464,.01,
.011064,.010571,
.010571,.011064,
.01,.011464,
.009368,.011759,
.008695,.011939,
.008,.012,
0.0*
%
%ADD41MACRO41*%
%AMMACRO65*
4,1,40,-.013,-.017,
.013,-.017,
.013695,-.016939,
.014368,-.016759,
.015,-.016464,
.015571,-.016064,
.016064,-.015571,
.016464,-.015,
.016759,-.014368,
.016939,-.013695,
.017,-.013,
.017,.013,
.016939,.013695,
.016759,.014368,
.016464,.015,
.016064,.015571,
.015571,.016064,
.015,.016464,
.014368,.016759,
.013695,.016939,
.013,.017,
-.013,.017,
-.013695,.016939,
-.014368,.016759,
-.015,.016464,
-.015571,.016064,
-.016064,.015571,
-.016464,.015,
-.016759,.014368,
-.016939,.013695,
-.017,.013,
-.017,-.013,
-.016939,-.013695,
-.016759,-.014368,
-.016464,-.015,
-.016064,-.015571,
-.015571,-.016064,
-.015,-.016464,
-.014368,-.016759,
-.013695,-.016939,
-.013,-.017,
0.0*
%
%ADD65MACRO65*%
%AMMACRO75*
4,1,40,.009,-.008,
.008939,-.008695,
.008759,-.009368,
.008464,-.01,
.008064,-.010571,
.007571,-.011064,
.007,-.011464,
.006368,-.011759,
.005695,-.011939,
.005,-.012,
-.005,-.012,
-.005695,-.011939,
-.006368,-.011759,
-.007,-.011464,
-.007571,-.011064,
-.008064,-.010571,
-.008464,-.01,
-.008759,-.009368,
-.008939,-.008695,
-.009,-.008,
-.009,.008,
-.008939,.008695,
-.008759,.009368,
-.008464,.01,
-.008064,.010571,
-.007571,.011064,
-.007,.011464,
-.006368,.011759,
-.005695,.011939,
-.005,.012,
.005,.012,
.005695,.011939,
.006368,.011759,
.007,.011464,
.007571,.011064,
.008064,.010571,
.008464,.01,
.008759,.009368,
.008939,.008695,
.009,.008,
.009,-.008,
0.0*
%
%ADD75MACRO75*%
%AMMACRO47*
4,1,40,-.017,.013,
-.017,-.013,
-.016939,-.013695,
-.016759,-.014368,
-.016464,-.015,
-.016064,-.015571,
-.015571,-.016064,
-.015,-.016464,
-.014368,-.016759,
-.013695,-.016939,
-.013,-.017,
.013,-.017,
.013695,-.016939,
.014368,-.016759,
.015,-.016464,
.015571,-.016064,
.016064,-.015571,
.016464,-.015,
.016759,-.014368,
.016939,-.013695,
.017,-.013,
.017,.013,
.016939,.013695,
.016759,.014368,
.016464,.015,
.016064,.015571,
.015571,.016064,
.015,.016464,
.014368,.016759,
.013695,.016939,
.013,.017,
-.013,.017,
-.013695,.016939,
-.014368,.016759,
-.015,.016464,
-.015571,.016064,
-.016064,.015571,
-.016464,.015,
-.016759,.014368,
-.016939,.013695,
-.017,.013,
0.0*
%
%ADD47MACRO47*%
%AMMACRO89*
4,1,40,-.008,-.009,
-.008695,-.008939,
-.009368,-.008759,
-.01,-.008464,
-.010571,-.008064,
-.011064,-.007571,
-.011464,-.007,
-.011759,-.006368,
-.011939,-.005695,
-.012,-.005,
-.012,.005,
-.011939,.005695,
-.011759,.006368,
-.011464,.007,
-.011064,.007571,
-.010571,.008064,
-.01,.008464,
-.009368,.008759,
-.008695,.008939,
-.008,.009,
.008,.009,
.008695,.008939,
.009368,.008759,
.01,.008464,
.010571,.008064,
.011064,.007571,
.011464,.007,
.011759,.006368,
.011939,.005695,
.012,.005,
.012,-.005,
.011939,-.005695,
.011759,-.006368,
.011464,-.007,
.011064,-.007571,
.010571,-.008064,
.01,-.008464,
.009368,-.008759,
.008695,-.008939,
.008,-.009,
-.008,-.009,
0.0*
%
%ADD89MACRO89*%
%ADD93R,.012X.05*%
%ADD84R,.05X.012*%
%ADD74R,.06X.02*%
%ADD101R,.042X.012*%
%ADD99R,.012X.042*%
%ADD81R,.06X.012*%
%ADD17R,.022X.04*%
%ADD92R,.012X.043*%
%ADD83R,.043X.012*%
%ADD117R,.012X.061*%
%ADD80R,.06X.014*%
%ADD78R,.081X.02*%
%ADD63R,.04X.016*%
%ADD51R,.044X.012*%
%ADD35R,.042X.014*%
%ADD34R,.014X.042*%
%ADD124R,.012X.044*%
%ADD115R,.014X.06*%
%ADD100R,.036X.012*%
%ADD98R,.012X.036*%
%ADD127R,.138X.14*%
%ADD118R,.016X.032*%
%ADD110R,.037X.012*%
%ADD109R,.012X.037*%
%ADD106R,.064X.03*%
%ADD104R,.03X.045*%
%ADD126R,.128X.133*%
%ADD62R,.115X.138*%
%ADD40R,.066X.02*%
%ADD73O,.06X.084*%
%ADD18R,.05X.065*%
%ADD95R,.055X.042*%
%ADD88R,.026X.036*%
%ADD39R,.065X.025*%
%ADD107R,.205X.197*%
%ADD105R,.09X.045*%
%ADD82R,.048X.016*%
%ADD77R,.025X.065*%
%ADD45R,.045X.055*%
%ADD66R,.016X.048*%
%ADD44R,.055X.045*%
%ADD43R,.055X.036*%
%ADD60C,.256*%
%ADD125R,.09X.095*%
%ADD79R,.059X.045*%
%ADD59R,.024X.079*%
%ADD103R,.045X.059*%
%ADD94R,.152X.152*%
%AMMACRO70*
4,1,40,-.0225,.007,
-.022378,.008389,
-.022018,.009736,
-.021428,.011,
-.020628,.012142,
-.019642,.013128,
-.0185,.013928,
-.017236,.014518,
-.015889,.014878,
-.0145,.015,
.0145,.015,
.015889,.014878,
.017236,.014518,
.0185,.013928,
.019642,.013128,
.020628,.012142,
.021428,.011,
.022018,.009736,
.022378,.008389,
.0225,.007,
.0225,-.007,
.022378,-.008389,
.022018,-.009736,
.021428,-.011,
.020628,-.012142,
.019642,-.013128,
.0185,-.013928,
.017236,-.014518,
.015889,-.014878,
.0145,-.015,
-.0145,-.015,
-.015889,-.014878,
-.017236,-.014518,
-.0185,-.013928,
-.019642,-.013128,
-.020628,-.012142,
-.021428,-.011,
-.022018,-.009736,
-.022378,-.008389,
-.0225,-.007,
-.0225,.007,
0.0*
%
%ADD70MACRO70*%
%AMMACRO69*
4,1,40,.014,.008,
.014,-.008,
.013939,-.008695,
.013759,-.009368,
.013464,-.01,
.013064,-.010571,
.012571,-.011064,
.012,-.011464,
.011368,-.011759,
.010695,-.011939,
.01,-.012,
-.01,-.012,
-.010695,-.011939,
-.011368,-.011759,
-.012,-.011464,
-.012571,-.011064,
-.013064,-.010571,
-.013464,-.01,
-.013759,-.009368,
-.013939,-.008695,
-.014,-.008,
-.014,.008,
-.013939,.008695,
-.013759,.009368,
-.013464,.01,
-.013064,.010571,
-.012571,.011064,
-.012,.011464,
-.011368,.011759,
-.010695,.011939,
-.01,.012,
.01,.012,
.010695,.011939,
.011368,.011759,
.012,.011464,
.012571,.011064,
.013064,.010571,
.013464,.01,
.013759,.009368,
.013939,.008695,
.014,.008,
0.0*
%
%ADD69MACRO69*%
%ADD61R,.095X.09*%
%ADD23C,.375*%
%ADD102R,.136X.136*%
%ADD33R,.128X.128*%
%ADD24R,.272X.272*%
%ADD113R,.093X.079*%
%AMMACRO49*
4,1,40,-.008,-.012,
.008,-.012,
.008695,-.011939,
.009368,-.011759,
.01,-.011464,
.010571,-.011064,
.011064,-.010571,
.011464,-.01,
.011759,-.009368,
.011939,-.008695,
.012,-.008,
.012,.008,
.011939,.008695,
.011759,.009368,
.011464,.01,
.011064,.010571,
.010571,.011064,
.01,.011464,
.009368,.011759,
.008695,.011939,
.008,.012,
-.008,.012,
-.008695,.011939,
-.009368,.011759,
-.01,.011464,
-.010571,.011064,
-.011064,.010571,
-.011464,.01,
-.011759,.009368,
-.011939,.008695,
-.012,.008,
-.012,-.008,
-.011939,-.008695,
-.011759,-.009368,
-.011464,-.01,
-.011064,-.010571,
-.010571,-.011064,
-.01,-.011464,
-.009368,-.011759,
-.008695,-.011939,
-.008,-.012,
0.0*
%
%ADD49MACRO49*%
%AMMACRO32*
4,1,40,.012,-.008,
.012,.008,
.011939,.008695,
.011759,.009368,
.011464,.01,
.011064,.010571,
.010571,.011064,
.01,.011464,
.009368,.011759,
.008695,.011939,
.008,.012,
-.008,.012,
-.008695,.011939,
-.009368,.011759,
-.01,.011464,
-.010571,.011064,
-.011064,.010571,
-.011464,.01,
-.011759,.009368,
-.011939,.008695,
-.012,.008,
-.012,-.008,
-.011939,-.008695,
-.011759,-.009368,
-.011464,-.01,
-.011064,-.010571,
-.010571,-.011064,
-.01,-.011464,
-.009368,-.011759,
-.008695,-.011939,
-.008,-.012,
.008,-.012,
.008695,-.011939,
.009368,-.011759,
.01,-.011464,
.010571,-.011064,
.011064,-.010571,
.011464,-.01,
.011759,-.009368,
.011939,-.008695,
.012,-.008,
0.0*
%
%ADD32MACRO32*%
%AMMACRO25*
4,1,40,-.007,-.011,
.007,-.011,
.007695,-.010939,
.008368,-.010759,
.009,-.010464,
.009571,-.010064,
.010064,-.009571,
.010464,-.009,
.010759,-.008368,
.010939,-.007695,
.011,-.007,
.011,.007,
.010939,.007695,
.010759,.008368,
.010464,.009,
.010064,.009571,
.009571,.010064,
.009,.010464,
.008368,.010759,
.007695,.010939,
.007,.011,
-.007,.011,
-.007695,.010939,
-.008368,.010759,
-.009,.010464,
-.009571,.010064,
-.010064,.009571,
-.010464,.009,
-.010759,.008368,
-.010939,.007695,
-.011,.007,
-.011,-.007,
-.010939,-.007695,
-.010759,-.008368,
-.010464,-.009,
-.010064,-.009571,
-.009571,-.010064,
-.009,-.010464,
-.008368,-.010759,
-.007695,-.010939,
-.007,-.011,
0.0*
%
%ADD25MACRO25*%
%AMMACRO10*
4,1,40,-.011,.007,
-.011,-.007,
-.010939,-.007695,
-.010759,-.008368,
-.010464,-.009,
-.010064,-.009571,
-.009571,-.010064,
-.009,-.010464,
-.008368,-.010759,
-.007695,-.010939,
-.007,-.011,
.007,-.011,
.007695,-.010939,
.008368,-.010759,
.009,-.010464,
.009571,-.010064,
.010064,-.009571,
.010464,-.009,
.010759,-.008368,
.010939,-.007695,
.011,-.007,
.011,.007,
.010939,.007695,
.010759,.008368,
.010464,.009,
.010064,.009571,
.009571,.010064,
.009,.010464,
.008368,.010759,
.007695,.010939,
.007,.011,
-.007,.011,
-.007695,.010939,
-.008368,.010759,
-.009,.010464,
-.009571,.010064,
-.010064,.009571,
-.010464,.009,
-.010759,.008368,
-.010939,.007695,
-.011,.007,
0.0*
%
%ADD10MACRO10*%
%AMMACRO56*
4,1,40,.013,.017,
-.013,.017,
-.013695,.016939,
-.014368,.016759,
-.015,.016464,
-.015571,.016064,
-.016064,.015571,
-.016464,.015,
-.016759,.014368,
-.016939,.013695,
-.017,.013,
-.017,-.013,
-.016939,-.013695,
-.016759,-.014368,
-.016464,-.015,
-.016064,-.015571,
-.015571,-.016064,
-.015,-.016464,
-.014368,-.016759,
-.013695,-.016939,
-.013,-.017,
.013,-.017,
.013695,-.016939,
.014368,-.016759,
.015,-.016464,
.015571,-.016064,
.016064,-.015571,
.016464,-.015,
.016759,-.014368,
.016939,-.013695,
.017,-.013,
.017,.013,
.016939,.013695,
.016759,.014368,
.016464,.015,
.016064,.015571,
.015571,.016064,
.015,.016464,
.014368,.016759,
.013695,.016939,
.013,.017,
0.0*
%
%ADD56MACRO56*%
%AMMACRO53*
4,1,6,.025,.0135,
.005,-.0065,
.005,-.0135,
-.005,-.0135,
-.005,-.0065,
-.025,.0135,
.025,.0135,
0.0*
%
%ADD53MACRO53*%
%AMMACRO14*
4,1,40,.017,-.013,
.017,.013,
.016939,.013695,
.016759,.014368,
.016464,.015,
.016064,.015571,
.015571,.016064,
.015,.016464,
.014368,.016759,
.013695,.016939,
.013,.017,
-.013,.017,
-.013695,.016939,
-.014368,.016759,
-.015,.016464,
-.015571,.016064,
-.016064,.015571,
-.016464,.015,
-.016759,.014368,
-.016939,.013695,
-.017,.013,
-.017,-.013,
-.016939,-.013695,
-.016759,-.014368,
-.016464,-.015,
-.016064,-.015571,
-.015571,-.016064,
-.015,-.016464,
-.014368,-.016759,
-.013695,-.016939,
-.013,-.017,
.013,-.017,
.013695,-.016939,
.014368,-.016759,
.015,-.016464,
.015571,-.016064,
.016064,-.015571,
.016464,-.015,
.016759,-.014368,
.016939,-.013695,
.017,-.013,
0.0*
%
%ADD14MACRO14*%
%AMMACRO91*
4,1,40,-.008,-.009,
-.008695,-.008939,
-.009368,-.008759,
-.01,-.008464,
-.010571,-.008064,
-.011064,-.007571,
-.011464,-.007,
-.011759,-.006368,
-.011939,-.005695,
-.012,-.005,
-.012,.005,
-.011939,.005695,
-.011759,.006368,
-.011464,.007,
-.011064,.007571,
-.010571,.008064,
-.01,.008464,
-.009368,.008759,
-.008695,.008939,
-.008,.009,
.008,.009,
.008695,.008939,
.009368,.008759,
.01,.008464,
.010571,.008064,
.011064,.007571,
.011464,.007,
.011759,.006368,
.011939,.005695,
.012,.005,
.012,-.005,
.011939,-.005695,
.011759,-.006368,
.011464,-.007,
.011064,-.007571,
.010571,-.008064,
.01,-.008464,
.009368,-.008759,
.008695,-.008939,
.008,-.009,
-.008,-.009,
0.0*
%
%ADD91MACRO91*%
%AMMACRO121*
4,1,20,.1095,.0655,
.1095,.051,
.12,.051,
.12,.0375,
.1095,.0375,
.1095,-.0375,
.12,-.0375,
.12,-.051,
.1095,-.051,
.1095,-.0655,
-.1095,-.0655,
-.1095,-.051,
-.12,-.051,
-.12,-.0375,
-.1095,-.0375,
-.1095,.0375,
-.12,.0375,
-.12,.051,
-.1095,.051,
-.1095,.0655,
.1095,.0655,
0.0*
%
%ADD121MACRO121*%
%AMMACRO96*
4,1,40,-.023,.013,
-.023,-.013,
-.022939,-.013695,
-.022759,-.014368,
-.022464,-.015,
-.022064,-.015571,
-.021571,-.016064,
-.021,-.016464,
-.020368,-.016759,
-.019695,-.016939,
-.019,-.017,
.019,-.017,
.019695,-.016939,
.020368,-.016759,
.021,-.016464,
.021571,-.016064,
.022064,-.015571,
.022464,-.015,
.022759,-.014368,
.022939,-.013695,
.023,-.013,
.023,.013,
.022939,.013695,
.022759,.014368,
.022464,.015,
.022064,.015571,
.021571,.016064,
.021,.016464,
.020368,.016759,
.019695,.016939,
.019,.017,
-.019,.017,
-.019695,.016939,
-.020368,.016759,
-.021,.016464,
-.021571,.016064,
-.022064,.015571,
-.022464,.015,
-.022759,.014368,
-.022939,.013695,
-.023,.013,
0.0*
%
%ADD96MACRO96*%
%AMMACRO50*
4,1,20,-.0655,.1095,
-.051,.1095,
-.051,.12,
-.0375,.12,
-.0375,.1095,
.0375,.1095,
.0375,.12,
.051,.12,
.051,.1095,
.0655,.1095,
.0655,-.1095,
.051,-.1095,
.051,-.12,
.0375,-.12,
.0375,-.1095,
-.0375,-.1095,
-.0375,-.12,
-.051,-.12,
-.051,-.1095,
-.0655,-.1095,
-.0655,.1095,
0.0*
%
%ADD50MACRO50*%
%AMMACRO122*
4,1,6,.0135,-.005,
.0065,-.005,
-.0135,-.025,
-.0135,.025,
.0065,.005,
.0135,.005,
.0135,-.005,
0.0*
%
%ADD122MACRO122*%
%AMMACRO111*
4,1,6,-.005,-.0135,
-.005,-.0065,
-.025,.0135,
.025,.0135,
.005,-.0065,
.005,-.0135,
-.005,-.0135,
0.0*
%
%ADD111MACRO111*%
%AMMACRO58*
4,1,15,-.0275,-.115,
-.0275,.115,
.0275,.115,
.0275,.06339,
.02431,.059697,
.021809,.055506,
.020074,.050945,
.019157,.046151,
.019087,.041272,
.019865,.036454,
.021468,.031844,
.023847,.027583,
.02693,.0238,
.0275,.02323,
.0275,-.115,
-.0275,-.115,
0.0*
%
%ADD58MACRO58*%
%AMMACRO48*
4,1,40,-.008,-.012,
.008,-.012,
.008695,-.011939,
.009368,-.011759,
.01,-.011464,
.010571,-.011064,
.011064,-.010571,
.011464,-.01,
.011759,-.009368,
.011939,-.008695,
.012,-.008,
.012,.008,
.011939,.008695,
.011759,.009368,
.011464,.01,
.011064,.010571,
.010571,.011064,
.01,.011464,
.009368,.011759,
.008695,.011939,
.008,.012,
-.008,.012,
-.008695,.011939,
-.009368,.011759,
-.01,.011464,
-.010571,.011064,
-.011064,.010571,
-.011464,.01,
-.011759,.009368,
-.011939,.008695,
-.012,.008,
-.012,-.008,
-.011939,-.008695,
-.011759,-.009368,
-.011464,-.01,
-.011064,-.010571,
-.010571,-.011064,
-.01,-.011464,
-.009368,-.011759,
-.008695,-.011939,
-.008,-.012,
0.0*
%
%ADD48MACRO48*%
%AMMACRO31*
4,1,40,.012,-.008,
.012,.008,
.011939,.008695,
.011759,.009368,
.011464,.01,
.011064,.010571,
.010571,.011064,
.01,.011464,
.009368,.011759,
.008695,.011939,
.008,.012,
-.008,.012,
-.008695,.011939,
-.009368,.011759,
-.01,.011464,
-.010571,.011064,
-.011064,.010571,
-.011464,.01,
-.011759,.009368,
-.011939,.008695,
-.012,.008,
-.012,-.008,
-.011939,-.008695,
-.011759,-.009368,
-.011464,-.01,
-.011064,-.010571,
-.010571,-.011064,
-.01,-.011464,
-.009368,-.011759,
-.008695,-.011939,
-.008,-.012,
.008,-.012,
.008695,-.011939,
.009368,-.011759,
.01,-.011464,
.010571,-.011064,
.011064,-.010571,
.011464,-.01,
.011759,-.009368,
.011939,-.008695,
.012,-.008,
0.0*
%
%ADD31MACRO31*%
%AMMACRO26*
4,1,40,-.007,-.011,
.007,-.011,
.007695,-.010939,
.008368,-.010759,
.009,-.010464,
.009571,-.010064,
.010064,-.009571,
.010464,-.009,
.010759,-.008368,
.010939,-.007695,
.011,-.007,
.011,.007,
.010939,.007695,
.010759,.008368,
.010464,.009,
.010064,.009571,
.009571,.010064,
.009,.010464,
.008368,.010759,
.007695,.010939,
.007,.011,
-.007,.011,
-.007695,.010939,
-.008368,.010759,
-.009,.010464,
-.009571,.010064,
-.010064,.009571,
-.010464,.009,
-.010759,.008368,
-.010939,.007695,
-.011,.007,
-.011,-.007,
-.010939,-.007695,
-.010759,-.008368,
-.010464,-.009,
-.010064,-.009571,
-.009571,-.010064,
-.009,-.010464,
-.008368,-.010759,
-.007695,-.010939,
-.007,-.011,
0.0*
%
%ADD26MACRO26*%
%AMMACRO11*
4,1,40,-.011,.007,
-.011,-.007,
-.010939,-.007695,
-.010759,-.008368,
-.010464,-.009,
-.010064,-.009571,
-.009571,-.010064,
-.009,-.010464,
-.008368,-.010759,
-.007695,-.010939,
-.007,-.011,
.007,-.011,
.007695,-.010939,
.008368,-.010759,
.009,-.010464,
.009571,-.010064,
.010064,-.009571,
.010464,-.009,
.010759,-.008368,
.010939,-.007695,
.011,-.007,
.011,.007,
.010939,.007695,
.010759,.008368,
.010464,.009,
.010064,.009571,
.009571,.010064,
.009,.010464,
.008368,.010759,
.007695,.010939,
.007,.011,
-.007,.011,
-.007695,.010939,
-.008368,.010759,
-.009,.010464,
-.009571,.010064,
-.010064,.009571,
-.010464,.009,
-.010759,.008368,
-.010939,.007695,
-.011,.007,
0.0*
%
%ADD11MACRO11*%
%ADD128C,.012*%
%ADD129C,.015*%
%ADD130C,.004*%
%ADD131C,.005*%
%ADD132C,.006*%
%ADD133C,.007*%
%ADD134C,.0049*%
%ADD135C,.00575*%
%ADD137O,.08402X.10802*%
%ADD138C,.06604*%
%ADD136R,.008X.008*%
G75*
%LPD*%
G75*
G36*
G01X26483Y752780D02*
X11125Y722062D01*
X10896D01*
X10750Y721916D01*
Y721708D01*
X10896Y721562D01*
X11000D01*
Y11000D01*
X109197D01*
Y40396D01*
X109343Y40437D01*
G03Y48147I-1075J3855D01*
G01X109197Y48188D01*
Y428627D01*
X117193D01*
Y3937D01*
G02X116260Y3004I-933J0D01*
G01X3937D01*
G02X3004Y3937I0J933D01*
G01Y723480D01*
G02X3103Y723897I933J-1D01*
G01X21284Y760260D01*
G02X22118Y760776I835J-417D01*
G01X386150D01*
G02X386984Y760260I-1J-933D01*
G01X405165Y723897D01*
G02X405264Y723480I-834J-418D01*
G01Y722062D01*
X397143D01*
X381785Y752780D01*
X379625D01*
X379565Y752853D01*
G03X348722Y752780I-15392J-12696D01*
G01X64663D01*
G03X33761I-15451J-12623D01*
G01X26483D01*
G37*
G36*
G01X34198Y548800D02*
G03X34349Y548122I1602J1D01*
G01X34368Y548082D01*
Y539146D01*
X34367Y539135D01*
G03X34356Y538954I1591J-188D01*
G01Y537554D01*
G03X34367Y537373I1602J7D01*
G01X34368Y537362D01*
Y535716D01*
X34382Y535702D01*
Y533581D01*
X34380Y533567D01*
G03X34364Y533338I1585J-226D01*
G01Y531938D01*
G03X34380Y531709I1601J-3D01*
G01X34382Y531695D01*
Y530297D01*
X56879Y507800D01*
X67500D01*
X67700Y507600D01*
X74405D01*
X74421Y507598D01*
G03X74673Y507578I252J1581D01*
G01X76073D01*
G03X76325Y507598I0J1601D01*
G01X76341Y507600D01*
X80032D01*
X80052Y507596D01*
G03X80368Y507564I319J1570D01*
G01X81768D01*
G03X82084Y507596I-3J1602D01*
G01X82104Y507600D01*
X85600D01*
X85650Y507650D01*
X88250D01*
X88400Y507500D01*
Y501300D01*
X87800Y500700D01*
X46711D01*
X24966Y522445D01*
Y571359D01*
X27920Y574313D01*
X43006D01*
X44600Y572719D01*
Y562123D01*
X41936Y559459D01*
X35929D01*
X34368Y557898D01*
Y550918D01*
X34349Y550878D01*
G03X34198Y550200I1451J-679D01*
G01Y548800D01*
G37*
G36*
G01X106365Y634516D02*
X108693Y636844D01*
Y656489D01*
X114920Y662716D01*
X124036D01*
X124807Y661945D01*
Y654627D01*
X123844Y653664D01*
X122618D01*
G03X119182Y652504I-1318J-1764D01*
G01X119168Y652454D01*
X115884Y649170D01*
Y629011D01*
X115468Y628595D01*
X115437Y628580D01*
G03X114420Y627563I963J-1980D01*
G01X114405Y627532D01*
X114174Y627301D01*
X102344D01*
X100321Y625278D01*
Y619023D01*
X98754Y617456D01*
X93658D01*
X80891Y604692D01*
X76619D01*
X69326Y597398D01*
Y593465D01*
X69493Y593297D01*
X63969Y587774D01*
X63947Y587761D01*
G03X63405Y587219I756J-1298D01*
G01X63392Y587197D01*
X61564Y585369D01*
Y581191D01*
X60276Y579903D01*
X58048D01*
X57178Y580773D01*
X54344Y583661D01*
Y598844D01*
X77247Y621747D01*
X82289D01*
X93779Y633237D01*
X102588D01*
G03X106350Y634479I1352J2223D01*
G01X106365Y634516D01*
G37*
G36*
G01X61454Y652008D02*
X62450Y651012D01*
Y648683D01*
X62449Y648675D01*
G03X62444Y648550I1597J-126D01*
G01Y647150D01*
G03X62449Y647025I1602J1D01*
G01X62450Y647017D01*
Y637250D01*
X62200Y637000D01*
X55714D01*
X54426Y638288D01*
Y657166D01*
X55460Y658200D01*
X61000D01*
X61200Y658000D01*
Y652400D01*
X61454Y652146D01*
Y652008D01*
G37*
G36*
G01X64300Y636300D02*
X63800Y636800D01*
Y644100D01*
X63830Y644130D01*
Y645030D01*
X64280Y645480D01*
X66600D01*
X67300Y646180D01*
Y652000D01*
X65056Y654244D01*
Y658200D01*
X73100D01*
X73148Y658248D01*
X73316D01*
Y658950D01*
X73402Y659036D01*
Y661390D01*
X78011D01*
X78400Y661000D01*
Y659800D01*
X79400Y658800D01*
X87598D01*
Y658702D01*
X93098D01*
X94400Y657400D01*
Y637300D01*
X93400Y636300D01*
X87696D01*
X87642Y636413D01*
G03X86200Y637318I-1442J-696D01*
G01X84600D01*
G03X83158Y636413I0J-1601D01*
G01X83104Y636300D01*
X64300D01*
G37*
G36*
G01X59309Y659451D02*
X59272Y659488D01*
Y662634D01*
X58566D01*
X58550Y662650D01*
X48850D01*
X48300Y663200D01*
Y668200D01*
X49100Y669000D01*
X59300D01*
X59400Y669100D01*
Y672291D01*
X72100D01*
Y669300D01*
X72156Y669245D01*
Y669066D01*
X78758D01*
Y669100D01*
X80919D01*
G03X80984Y669098I82J1599D01*
G01X82584D01*
G03X82649Y669100I-17J1601D01*
G01X96200D01*
X97200Y668100D01*
Y660900D01*
X96350Y660050D01*
X81550D01*
X79000Y662600D01*
X78758D01*
Y662634D01*
X72156D01*
Y659490D01*
X72117Y659451D01*
X59309D01*
G37*
G36*
G01X78758Y670302D02*
Y670310D01*
X73390D01*
X73316Y670384D01*
Y673452D01*
X73302D01*
Y673502D01*
X71848D01*
X71800Y673550D01*
X65056D01*
Y678894D01*
X65000D01*
Y679274D01*
X68310Y682584D01*
X77612D01*
X80329Y685301D01*
X90286D01*
X90598Y684989D01*
Y671474D01*
X89426Y670302D01*
X78758D01*
G37*
G36*
G01X137600Y626200D02*
Y621783D01*
X137592Y621755D01*
G03X137492Y621164I2498J-727D01*
G01X137488Y621088D01*
X136056Y619656D01*
X134995D01*
G03X134601Y619606I3J-1602D01*
G01X134576Y619600D01*
X133414D01*
X133389Y619606D01*
G03X132995Y619656I-397J-1552D01*
G01X131595D01*
G03X131201Y619606I3J-1602D01*
G01X131176Y619600D01*
X123600D01*
X122800Y618800D01*
X117500D01*
X117200Y619100D01*
Y622500D01*
X117600Y622900D01*
X121087D01*
X122034Y623847D01*
Y625313D01*
X122707Y625986D01*
X129986D01*
X130398Y626398D01*
X137402D01*
X137600Y626200D01*
G37*
G36*
G01X118900Y627702D02*
G03X118789Y627698I2J-1602D01*
G01X118699Y627691D01*
X118500Y627890D01*
Y630500D01*
X121400Y633400D01*
X137800D01*
X138000Y633200D01*
X139300D01*
X140100Y632400D01*
Y628700D01*
X139000Y627600D01*
X137362D01*
X137330Y627611D01*
G03X136800Y627702I-532J-1511D01*
G01X135200D01*
G03X134670Y627611I2J-1602D01*
G01X134638Y627600D01*
X120862D01*
X120830Y627611D01*
G03X120300Y627702I-532J-1511D01*
G01X118900D01*
G37*
G36*
G01X75100Y623500D02*
X74400Y624200D01*
Y631141D01*
X76259Y633000D01*
X81600D01*
X83198Y631402D01*
Y629784D01*
G03X83200Y629706I2202J17D01*
G01Y624600D01*
X82100Y623500D01*
X75100D01*
G37*
G36*
G01X136300Y634800D02*
X136000Y635100D01*
X126500D01*
X126484Y635116D01*
X118685D01*
X118000Y635801D01*
Y639800D01*
X118300Y640100D01*
X118535D01*
G03X118600Y640098I82J1599D01*
G01X120200D01*
G03X120265Y640100I-17J1601D01*
G01X122235D01*
G03X122300Y640098I82J1599D01*
G01X123900D01*
G03X123965Y640100I-17J1601D01*
G01X138600D01*
X139400Y639300D01*
Y634800D01*
X136300D01*
G37*
G36*
G01X101101Y670404D02*
X92564D01*
X91844Y671124D01*
Y686291D01*
X92705Y687152D01*
X100782D01*
X101620Y686314D01*
Y670923D01*
X101101Y670404D01*
G37*
G36*
G01X118298Y641302D02*
X118200Y641400D01*
Y647600D01*
X118650Y648050D01*
X119650D01*
X119700Y648100D01*
X128800D01*
X129300Y647600D01*
Y642000D01*
X128602Y641302D01*
X118298D01*
G37*
G36*
G01X130349Y697215D02*
X128349Y699215D01*
Y703200D01*
X128778D01*
Y704478D01*
X128900Y704600D01*
Y734300D01*
X129800Y735200D01*
X135400D01*
X136000Y734600D01*
Y726200D01*
X136410Y725790D01*
X138750D01*
Y726850D01*
X140100D01*
X140120Y726830D01*
Y725890D01*
X140180Y725830D01*
X140190Y725840D01*
X141260D01*
Y713043D01*
X141349D01*
Y699215D01*
X139349Y697215D01*
X136402D01*
Y697402D01*
X132998D01*
Y697215D01*
X130349D01*
G37*
G36*
G01X138349Y684215D02*
X111849D01*
X111349Y684715D01*
Y693715D01*
X112317Y694683D01*
X118700D01*
X119100Y694283D01*
Y692600D01*
X119800Y691900D01*
X124100D01*
X128131Y695931D01*
X131252D01*
X132500Y694683D01*
X137881D01*
X138849Y693715D01*
Y684715D01*
X138349Y684215D01*
G37*
G36*
G01X130800Y642900D02*
X130600Y643100D01*
Y647700D01*
X130502Y647799D01*
Y648098D01*
X130100Y648499D01*
Y650800D01*
X130900Y651600D01*
X136900D01*
X137400Y651100D01*
Y647800D01*
X136800Y647200D01*
Y643100D01*
X136600Y642900D01*
X130800D01*
G37*
G36*
G01X119055Y734715D02*
X91085D01*
X89700Y736100D01*
Y746500D01*
X89915Y746715D01*
X125849D01*
X128410Y744154D01*
Y738110D01*
X127660Y737360D01*
X121700D01*
X119055Y734715D01*
G37*
G36*
G01X89939Y717877D02*
X81551D01*
X81232Y718196D01*
Y724247D01*
X81314Y724328D01*
Y725240D01*
X82693Y726619D01*
X90503D01*
X90637Y726485D01*
Y718575D01*
X89939Y717877D01*
G37*
G36*
G01X114319Y715696D02*
G03X113197Y715238I-1J-1601D01*
G02X112929Y715227I-140J143D01*
G03X111900Y715602I-1030J-1227D01*
G01X110500D01*
G03X109292Y715052I0J-1602D01*
G01X108255D01*
X107919Y714715D01*
X95544D01*
X93258Y717001D01*
Y726597D01*
X91236Y728619D01*
Y733183D01*
X98817D01*
X98849Y733215D01*
X119705D01*
X122100Y735610D01*
X127070D01*
X127660Y735020D01*
Y728001D01*
X127349Y727690D01*
Y726996D01*
X127268D01*
Y715634D01*
X126349Y714715D01*
X118401D01*
X118345Y714824D01*
G03X116919Y715696I-1426J-730D01*
G01X114319D01*
G37*
G36*
G01X154300Y511300D02*
X154036Y511564D01*
Y513846D01*
X157190Y517000D01*
X162700D01*
X162800Y516900D01*
Y512200D01*
X161900Y511300D01*
X154300D01*
G37*
G36*
G01X198879Y635879D02*
X198400Y635400D01*
X192333D01*
X192301Y635411D01*
G03X191776Y635500I-526J-1513D01*
G01X190376D01*
G03X189851Y635411I1J-1602D01*
G01X189819Y635400D01*
X177100D01*
X176400Y636100D01*
X175465D01*
G03X175400Y636102I-82J-1599D01*
G01X174000D01*
G03X173935Y636100I17J-1601D01*
G01X171365D01*
G03X171300Y636102I-82J-1599D01*
G01X169900D01*
G03X169835Y636100I17J-1601D01*
G01X169600D01*
X169300Y636400D01*
Y640560D01*
X170370Y641630D01*
X198520D01*
X199400Y640750D01*
Y638151D01*
G03X198847Y635992I1563J-1551D01*
G01X198879Y635879D01*
G37*
G36*
G01X217900Y643000D02*
X217165Y643735D01*
X217285Y643875D01*
G03X213540Y644538I-1679J1425D01*
G02X213165Y644000I-375J-138D01*
G01X207200D01*
X206800Y644400D01*
Y650100D01*
X209900Y653200D01*
X213890D01*
X213898Y653199D01*
G03X214023Y653194I126J1597D01*
G01X215423D01*
G03X215548Y653199I-1J1602D01*
G01X215556Y653200D01*
X219600D01*
X220600Y652200D01*
Y641300D01*
X220400Y641100D01*
X219965D01*
G03X219900Y641102I-82J-1599D01*
G01X218500D01*
G03X218435Y641100I17J-1601D01*
G01X218000D01*
X217900Y641200D01*
Y643000D01*
G37*
G36*
G01X189998Y703002D02*
X188500Y704500D01*
Y715400D01*
X190500Y717400D01*
X203500D01*
X206800Y714100D01*
X228000D01*
X228900Y713200D01*
Y704900D01*
X227002Y703002D01*
X189998D01*
G37*
G36*
G01X161420Y714715D02*
X143349D01*
X142849Y715215D01*
Y728910D01*
X141189Y730570D01*
Y735940D01*
X142749Y737500D01*
X145600D01*
X146300Y738200D01*
Y741488D01*
X147000Y742188D01*
X162332D01*
X164580Y739940D01*
Y717875D01*
X161420Y714715D01*
G37*
G36*
G01X230600Y711400D02*
X230102Y711898D01*
Y713698D01*
X229800Y713999D01*
Y714600D01*
X229100Y715300D01*
X228499D01*
X228498Y715302D01*
X226758D01*
X226726Y715313D01*
G03X226200Y715402I-527J-1513D01*
G01X224600D01*
G03X224074Y715313I1J-1602D01*
G01X224042Y715302D01*
X207422D01*
X203924Y718800D01*
X173400D01*
X172812Y719388D01*
Y742000D01*
X174512Y743700D01*
X234200D01*
X235400Y742500D01*
Y712500D01*
X234300Y711400D01*
X230600D01*
G37*
G36*
G01X278220Y712420D02*
X278902Y713102D01*
X279023Y713057D01*
G03X281128Y713220I877J2343D01*
G01X289220D01*
X289320Y713320D01*
Y716511D01*
X302020D01*
Y713520D01*
X302076Y713464D01*
Y713286D01*
X308678D01*
Y713320D01*
X310839D01*
G03X310904Y713318I82J1599D01*
G01X312504D01*
G03X312569Y713320I-17J1601D01*
G01X326120D01*
X327120Y712320D01*
Y705120D01*
X326270Y704270D01*
X326200D01*
X325930Y704000D01*
X311100D01*
X310800Y704300D01*
Y704940D01*
X308920Y706820D01*
X308678D01*
Y706854D01*
X302076D01*
Y706822D01*
X302018D01*
Y703718D01*
X301965Y703665D01*
X289192D01*
Y706854D01*
X288486D01*
X288470Y706870D01*
X278770D01*
X278220Y707420D01*
Y712420D01*
G37*
G36*
G01X249300Y715000D02*
X240600D01*
X239050Y716550D01*
Y742500D01*
X240025Y743475D01*
X250525D01*
X251900Y742100D01*
Y717600D01*
X249300Y715000D01*
G37*
G36*
G01X903913Y760260D02*
X922094Y723897D01*
G02X922193Y723480I-834J-418D01*
G01Y3937D01*
G02X921260Y3004I-933J0D01*
G01X291457D01*
G02X290524Y3937I0J933D01*
G01Y141799D01*
X298520D01*
Y11000D01*
X429547D01*
X430607Y9940D01*
X535656D01*
X536716Y11000D01*
X914197D01*
Y721812D01*
X898714Y752780D01*
X891435D01*
G03X860592Y752853I-15451J-12623D01*
G01X860532Y752780D01*
X857457D01*
Y747562D01*
X857443Y747526D01*
G03X857457Y732752I18541J-7369D01*
G01Y633858D01*
G02X842520Y618921I-14937J0D01*
G01X627656D01*
G03X596812Y618994I-15452J-12622D01*
G01X596752Y618921D01*
X594593D01*
X579110Y587953D01*
Y488787D01*
G03X571888Y479496I11441J-16346D01*
G02X571114Y479638I-374J142D01*
G01Y589621D01*
G02X571213Y590038I933J-1D01*
G01X589394Y626401D01*
G02X590228Y626917I835J-417D01*
G01X842520D01*
G03X849461Y633858I0J6941D01*
G01Y759843D01*
G02X850394Y760776I933J0D01*
G01X903079D01*
G02X903913Y760260I-1J-933D01*
G37*
G36*
G01X372900Y128000D02*
X371500Y126600D01*
X367613D01*
G03X365387I-1113J-1900D01*
G01X364021D01*
G03X362179I-921J-2000D01*
G01X358600D01*
X358038Y126038D01*
Y118937D01*
X357380Y118279D01*
X349137D01*
X348404Y117546D01*
X348351Y117533D01*
G03X346836Y116168I549J-2133D01*
G01X346788Y116038D01*
X330326D01*
X328843Y117521D01*
Y123286D01*
X330512Y124955D01*
X345900D01*
X346459Y125514D01*
X346527Y125522D01*
G03X347924Y126919I-193J1590D01*
G01X347932Y126987D01*
X351845Y130900D01*
X357700D01*
X358600Y131800D01*
Y139900D01*
X360100Y141400D01*
X372200D01*
X372900Y140700D01*
Y128000D01*
G37*
G36*
G01X350272Y79115D02*
X348893Y77736D01*
X347811D01*
X347773Y77753D01*
G03X345104Y77736I-1315J-3029D01*
G01X337589D01*
X328539Y86786D01*
Y112307D01*
X330281Y114049D01*
X335901D01*
X336755Y113195D01*
Y107986D01*
X336770Y107970D01*
Y107830D01*
X338700Y105900D01*
X350900D01*
X351638Y105162D01*
Y105089D01*
G03X351636Y105000I1599J-80D01*
G01Y103400D01*
G03X351638Y103316I1601J-4D01*
G01Y89232D01*
G03Y83838I1905J-2697D01*
G01Y81358D01*
G03X350282Y79179I1905J-2697D01*
G01X350272Y79115D01*
G37*
G36*
G01X351012Y186602D02*
X350100Y187513D01*
Y195200D01*
X350300Y195400D01*
X353200D01*
X355120Y193480D01*
Y191828D01*
X355200Y191747D01*
Y187283D01*
G03X355007Y186765I1382J-810D01*
G01X354977Y186602D01*
X351012D01*
G37*
G36*
G01X362600Y156500D02*
X354100Y165000D01*
Y174300D01*
X354400Y174600D01*
X357800D01*
X358460Y173940D01*
X358468Y173929D01*
G03X358844Y173553I1591J1215D01*
G01X358855Y173545D01*
X363300Y169100D01*
X371500D01*
X372900Y167700D01*
Y157200D01*
X372200Y156500D01*
X362600D01*
G37*
G36*
G01X310781Y194919D02*
X308000Y197700D01*
X307230D01*
X307184Y197727D01*
G03X304573Y197722I-1301J-2253D01*
G01X304100Y198195D01*
Y200030D01*
X304565Y200494D01*
X305703D01*
G03X305748Y200495I-26J2201D01*
G01X307695D01*
X310300Y203100D01*
X322600D01*
X323200Y202500D01*
Y195700D01*
X322419Y194919D01*
X310781D01*
G37*
G36*
G01X293400Y188500D02*
X292900Y189000D01*
Y199700D01*
X293164Y199964D01*
X302536D01*
X302898Y199601D01*
Y197697D01*
X304097Y196498D01*
X307402D01*
X307500Y196400D01*
Y188900D01*
X307100Y188500D01*
X293400D01*
G37*
G36*
G01X342600Y185700D02*
X340000Y188300D01*
X335200D01*
X333700Y189800D01*
Y202200D01*
X334900Y203400D01*
X352900D01*
X353200Y203100D01*
Y196900D01*
X352901Y196602D01*
X349802D01*
X349801Y196600D01*
X349600D01*
X348900Y195900D01*
Y195699D01*
X348898Y195698D01*
Y194518D01*
X348897Y194504D01*
G03X348880Y194278I1584J-233D01*
G01Y192878D01*
G03X348897Y192652I1601J7D01*
G01X348898Y192638D01*
Y190818D01*
X348897Y190804D01*
G03X348880Y190578I1584J-233D01*
G01Y188978D01*
G03X348897Y188752I1601J7D01*
G01X348898Y188738D01*
Y187698D01*
X346900Y185700D01*
X342600D01*
G37*
G36*
G01X322699Y207900D02*
X319928Y210671D01*
X310565D01*
X310537Y210699D01*
Y212382D01*
X310718Y212562D01*
X319918D01*
Y212565D01*
X320273D01*
X331308Y223600D01*
X357600D01*
X357882Y223318D01*
Y216698D01*
X357348Y216164D01*
Y209248D01*
X356000Y207900D01*
X322699D01*
G37*
G36*
G01X293300Y217000D02*
X292900Y217400D01*
Y228200D01*
X293000Y228300D01*
X301100D01*
X304200Y225200D01*
X306200D01*
X306746Y225746D01*
G03X307110Y226110I-1364J1728D01*
G01X308300Y227300D01*
Y231000D01*
X308800Y231500D01*
X309414D01*
Y231460D01*
X318840D01*
X319000Y231300D01*
Y220400D01*
X318714Y220114D01*
X309414D01*
Y220100D01*
X309200D01*
X308400Y219300D01*
Y217600D01*
X307800Y217000D01*
X293300D01*
G37*
G36*
G01X291400Y636888D02*
Y641000D01*
X292150Y641750D01*
X299886D01*
X299986Y641850D01*
Y644381D01*
X300605Y645000D01*
X312065D01*
X312686Y644379D01*
Y642050D01*
X312742Y641994D01*
Y641816D01*
X319366D01*
X320750Y643200D01*
X321135D01*
G03X321200Y643198I82J1599D01*
G01X322800D01*
G03X322865Y643200I-17J1601D01*
G01X323350D01*
X324700Y641850D01*
X331177D01*
G03X333223I1023J1950D01*
G01X336000D01*
X336600Y641250D01*
Y639300D01*
X335200Y637900D01*
Y632800D01*
X322136D01*
X319586Y635350D01*
X319344D01*
Y635384D01*
X312742D01*
Y635256D01*
X312700Y635214D01*
Y632264D01*
X312636Y632200D01*
X299858D01*
Y635384D01*
X299152D01*
X299136Y635400D01*
X292888D01*
X291400Y636888D01*
G37*
G36*
G01X334358Y607700D02*
X327600D01*
X327100Y608200D01*
Y622700D01*
X327900Y623500D01*
X336300D01*
X337100Y622700D01*
Y610442D01*
X334358Y607700D01*
G37*
G36*
G01X301069Y598251D02*
X301029Y598399D01*
G03X299036Y600216I-2416J-649D01*
G01X298973Y600227D01*
X298800Y600400D01*
Y604300D01*
X299900Y605400D01*
X306919D01*
X308019Y604300D01*
X314480D01*
X314490Y604310D01*
X314892Y603908D01*
Y598592D01*
X314500Y598200D01*
X307740D01*
G03X307560I-90J-2200D01*
G01X304302D01*
X304251Y598251D01*
X301069D01*
G37*
G36*
G01X298650Y609750D02*
X297102Y611298D01*
Y621156D01*
X297100Y621157D01*
Y623414D01*
X300400Y626714D01*
Y630850D01*
X300500Y630950D01*
X301586D01*
X301786Y630750D01*
Y623814D01*
X304160Y621440D01*
X304155Y621350D01*
G03X304152Y621250I1598J-98D01*
G01Y619850D01*
G03X304164Y619651I1601J-3D01*
G01X304176Y619554D01*
X303036Y618414D01*
Y610000D01*
X302786Y609750D01*
X298650D01*
G37*
G36*
G01X307236Y606700D02*
X304386Y609550D01*
Y611033D01*
X304395Y611062D01*
G03X304472Y611550I-1525J491D01*
G01Y613150D01*
G03X304395Y613638I-1602J-3D01*
G01X304386Y613667D01*
Y616850D01*
X304416Y616880D01*
Y617100D01*
X304816Y617500D01*
X307600D01*
X309200Y619100D01*
Y623600D01*
X308032Y624768D01*
X307868D01*
X305642Y626994D01*
Y630950D01*
X313686D01*
X313734Y630998D01*
X313902D01*
Y634140D01*
X318596D01*
X318986Y633750D01*
Y632550D01*
X319986Y631550D01*
X334850D01*
X335400Y631000D01*
Y625400D01*
X335200Y625200D01*
X326000D01*
X325100Y624300D01*
Y608600D01*
X319850D01*
X319400Y609050D01*
X319081D01*
X319043Y609067D01*
G03X318400Y609202I-644J-1467D01*
G01X316800D01*
G03X316157Y609067I1J-1602D01*
G01X316119Y609050D01*
X315200D01*
X314900Y608750D01*
Y607000D01*
X314600Y606700D01*
X307236D01*
G37*
G36*
G01X321440Y657456D02*
X322022Y656874D01*
X322026Y656797D01*
G03X323808Y654910I1999J103D01*
G01X323986Y654891D01*
Y645200D01*
X323188Y644402D01*
X320252D01*
X318911Y643060D01*
X313976D01*
X313902Y643134D01*
Y646202D01*
X312484D01*
X312386Y646300D01*
X305642D01*
Y651644D01*
X305586D01*
Y652893D01*
G03Y655297I-1845J1202D01*
G01Y656632D01*
X305599Y656666D01*
G03X305702Y657230I-1499J565D01*
G01Y658830D01*
G03X305599Y659394I-1602J-1D01*
G01X305586Y659428D01*
Y660232D01*
X305599Y660266D01*
G03X305696Y660693I-1499J565D01*
G01X305702Y660766D01*
X306386Y661450D01*
X320430D01*
X321440Y660440D01*
Y657456D01*
G37*
G36*
G01X297594Y672506D02*
X297500Y672600D01*
Y677200D01*
X298070Y677770D01*
X311816D01*
X312233Y677353D01*
Y673687D01*
X311052Y672506D01*
X304743D01*
G03X301815I-1464J-2029D01*
G01X297594D01*
G37*
G36*
G01X286018Y681220D02*
X285082Y682156D01*
Y687346D01*
X285066D01*
X284635Y687777D01*
Y701187D01*
X285868Y702420D01*
X290920D01*
X291120Y702220D01*
Y695814D01*
X292480Y694454D01*
Y689679D01*
X292394Y689593D01*
Y681494D01*
X292120Y681220D01*
X286018D01*
G37*
G36*
G01X294220Y680520D02*
X293595Y681145D01*
Y683173D01*
X293598Y683190D01*
G03X293620Y683453I-1580J265D01*
G01Y684853D01*
G03X293598Y685116I-1602J-2D01*
G01X293595Y685133D01*
Y687137D01*
X293596Y687147D01*
G03X293606Y687320I-1592J179D01*
G01Y688920D01*
G03X293603Y689009I-1602J-9D01*
G01X293598Y689098D01*
X293944Y689444D01*
X296264D01*
X297220Y690400D01*
Y696220D01*
X294976Y698464D01*
Y702420D01*
X303020D01*
X303068Y702468D01*
X303236D01*
Y705610D01*
X307686D01*
X307982Y705313D01*
Y703445D01*
X310091Y701336D01*
X323865D01*
X324320Y700881D01*
Y681520D01*
X323320Y680520D01*
X322994D01*
X322949Y680545D01*
G03X322175Y680744I-773J-1402D01*
G01X320775D01*
G03X320249Y680656I-2J-1601D01*
G01X320217Y680644D01*
X317261D01*
X317137Y680520D01*
X316082D01*
X316050Y680531D01*
G03X315520Y680622I-532J-1511D01*
G01X313920D01*
G03X313390Y680531I2J-1602D01*
G01X313358Y680520D01*
X294220D01*
G37*
G36*
G01X308678Y714522D02*
Y714530D01*
X303310D01*
X303236Y714604D01*
Y717672D01*
X303222D01*
Y717722D01*
X301768D01*
X301720Y717770D01*
X294976D01*
Y723114D01*
X294920D01*
Y725398D01*
G03Y727802I-1845J1202D01*
G01Y732120D01*
X295000Y732200D01*
Y733200D01*
X295600Y733800D01*
X311000D01*
X313320Y731480D01*
Y714920D01*
X312922Y714522D01*
X308678D01*
G37*
G36*
G01X367300Y118200D02*
X367000Y118500D01*
X360000D01*
Y123500D01*
X361899Y125398D01*
X371502D01*
X372100Y124800D01*
Y118800D01*
X371500Y118200D01*
X370762D01*
X370730Y118211D01*
G03X370200Y118302I-532J-1511D01*
G01X368600D01*
G03X368070Y118211I2J-1602D01*
G01X368038Y118200D01*
X367300D01*
G37*
G36*
G01X373270Y183449D02*
X372881Y183838D01*
Y188494D01*
X372900Y188534D01*
G03X373052Y189214I-1450J681D01*
G01Y190814D01*
G03X372900Y191494I-1602J-1D01*
G01X372881Y191534D01*
Y192094D01*
X372900Y192134D01*
G03X373052Y192814I-1450J681D01*
G01Y194414D01*
G03X373007Y194789I-1602J-2D01*
G01X373002Y194812D01*
Y197957D01*
X372907Y198051D01*
X372905Y198131D01*
G03X372884Y198354I-1601J-38D01*
G01X372881Y198371D01*
Y198732D01*
X372643Y198970D01*
X372632Y198986D01*
G03X372184Y199429I-1328J-895D01*
G01X371436Y200177D01*
Y203513D01*
X372401Y204478D01*
X375786D01*
X376564Y203700D01*
Y183917D01*
X376096Y183449D01*
X375716D01*
X375708Y183450D01*
G03X375583Y183454I-114J-1597D01*
G01X374183D01*
G03X374058Y183450I-11J-1601D01*
G01X374050Y183449D01*
X373270D01*
G37*
G36*
G01X374900Y575050D02*
Y575826D01*
X374921Y575868D01*
G03X375070Y576254I-1970J982D01*
G01X375111Y576400D01*
X377200D01*
X377700Y576900D01*
Y579181D01*
G03X377671Y581084I-2000J921D01*
G01X377650Y581126D01*
Y581516D01*
X377864D01*
X377878Y581514D01*
G03X378100Y581498I226J1586D01*
G01X379500D01*
G03X380570Y581908I0J1601D01*
G01X381230D01*
G03X382300Y581498I1070J1191D01*
G01X383700D01*
G03X384770Y581908I0J1601D01*
G01X388308D01*
X389150Y582750D01*
X391150D01*
X391900Y583500D01*
Y594400D01*
X392300Y594800D01*
X397100D01*
X398500Y596200D01*
Y598500D01*
X397300Y599700D01*
X392800D01*
X391902Y600598D01*
Y602000D01*
G03X391900Y602065I-1601J-17D01*
G01Y604635D01*
G03X391902Y604700I-1599J82D01*
G01Y606100D01*
G03X391900Y606165I-1601J-17D01*
G01Y606500D01*
X392500Y607100D01*
X395800D01*
X397200Y608500D01*
Y613100D01*
X393500Y616800D01*
X390300D01*
X390113Y616987D01*
X390125Y617083D01*
G03X390138Y617280I-1589J204D01*
G01Y618680D01*
G03X390136Y618745I-1601J-17D01*
G01X390133Y618833D01*
X390850Y619550D01*
X393950D01*
X395000Y620600D01*
Y624100D01*
X392518Y626582D01*
G03X391705Y627405I-1918J-1082D01*
G01X391682Y627418D01*
X391513Y627587D01*
X391525Y627683D01*
G03X391538Y627880I-1589J204D01*
G01Y629280D01*
G03X391504Y629605I-1602J-3D01*
G01X391500Y629625D01*
Y637135D01*
G03X391502Y637200I-1599J82D01*
G01Y638600D01*
G03X391500Y638665I-1601J-17D01*
G01Y638900D01*
X392200Y639600D01*
X398800D01*
X399964Y638436D01*
Y593864D01*
X394175Y588075D01*
Y587578D01*
X394169Y587553D01*
G03Y586447I2131J-553D01*
G01X394175Y586422D01*
Y581225D01*
X392900Y579950D01*
X389350D01*
X387800Y578400D01*
Y575800D01*
X387700Y575700D01*
X384773D01*
X384742Y575710D01*
G03X383146I-798J-2371D01*
G01X383115Y575700D01*
X381600D01*
X381400Y575500D01*
Y575400D01*
X381050Y575050D01*
X374900D01*
G37*
G36*
G01X405264Y702285D02*
X397268D01*
Y719900D01*
X405264D01*
Y702285D01*
G37*
G36*
G01X492403Y36300D02*
X492103Y36600D01*
Y43003D01*
X494400Y45297D01*
Y49910D01*
G03X495419Y50900I-1162J2216D01*
G01X500984D01*
X501400Y50484D01*
Y47051D01*
X498696Y44347D01*
Y39003D01*
X495993Y36300D01*
X494365D01*
G03X494300Y36302I-82J-1599D01*
G01X492900D01*
G03X492835Y36300I17J-1601D01*
G01X492403D01*
G37*
G36*
G01X436860Y19500D02*
X430000Y26360D01*
Y56204D01*
X431252Y57456D01*
X436720D01*
X436900Y57276D01*
Y55900D01*
X435300Y54300D01*
Y38987D01*
X435298Y38973D01*
G03X435284Y38757I1587J-211D01*
G01Y37357D01*
G03X435298Y37141I1601J-5D01*
G01X435300Y37127D01*
Y35300D01*
X435500Y35100D01*
X440200D01*
X441300Y36200D01*
Y38900D01*
X441700Y39300D01*
X443500D01*
X443700Y39100D01*
Y22887D01*
X443698Y22873D01*
G03X443684Y22657I1587J-211D01*
G01Y21257D01*
G03X443698Y21041I1601J-5D01*
G01X443700Y21027D01*
Y20800D01*
X442400Y19500D01*
X436860D01*
G37*
G36*
G01X505830Y26092D02*
X501851D01*
X498900Y29043D01*
Y30800D01*
X496600Y33100D01*
Y35000D01*
X499272Y37672D01*
X505795D01*
X506584Y36883D01*
Y30826D01*
X506064Y30305D01*
Y26326D01*
X505830Y26092D01*
G37*
G36*
G01X539996Y51877D02*
Y54100D01*
X539919D01*
Y59647D01*
X538166Y61400D01*
X520325D01*
G03X517455I-1435J-1670D01*
G01X514865D01*
X514347Y60882D01*
X509781Y60890D01*
X501370Y69301D01*
X491913D01*
X489718Y71496D01*
Y81082D01*
X490686Y82049D01*
X498028D01*
X498049Y82045D01*
G03X498951I451J2155D01*
G01X498972Y82049D01*
X510936D01*
X513403Y79582D01*
Y73867D01*
X515440Y71830D01*
X515700D01*
X515731Y71798D01*
X549168D01*
X550328Y70639D01*
Y52391D01*
X549814Y51877D01*
X539996D01*
G37*
G36*
G01X510353Y16855D02*
X502520D01*
X501524Y17851D01*
Y23313D01*
X503078Y24867D01*
X510234D01*
X510891Y24210D01*
Y17393D01*
X510353Y16855D01*
G37*
G36*
G01X552700Y85900D02*
X558046Y80554D01*
Y52846D01*
X556965Y51765D01*
X552165D01*
X551600Y52330D01*
Y60335D01*
G03X551602Y60400I-1599J82D01*
G01Y62000D01*
G03X551600Y62065I-1601J-17D01*
G01Y72016D01*
X550616Y73000D01*
X516229D01*
X515450Y73779D01*
Y82524D01*
X515454Y82544D01*
G03X515457Y83442I-2154J456D01*
G01X515436Y83548D01*
X517788Y85900D01*
X552700D01*
G37*
G36*
G01X520691Y16142D02*
X519528Y17305D01*
Y28962D01*
X520051Y29485D01*
X520645D01*
X520675Y29475D01*
G03X522311I818J2470D01*
G01X522341Y29485D01*
X525101D01*
X525551Y29035D01*
Y27424D01*
X526714Y26261D01*
X533870D01*
X534206Y25925D01*
Y20582D01*
X534290D01*
Y16924D01*
X533508Y16142D01*
X520691D01*
G37*
G36*
G01X513181Y19350D02*
X512113Y20418D01*
Y25330D01*
X511140Y26303D01*
X507510D01*
X507336Y26477D01*
Y29545D01*
X507726Y29934D01*
X507994Y30202D01*
Y44629D01*
X508490Y45125D01*
X513544D01*
X514086Y44583D01*
Y30854D01*
X515444Y29496D01*
X515813D01*
X515845Y29485D01*
G03X517541I848J2460D01*
G01X517573Y29496D01*
X517850D01*
X518300Y29046D01*
Y20191D01*
X517459Y19350D01*
X513181D01*
G37*
G36*
G01X536000Y21048D02*
X535495Y21553D01*
Y27115D01*
X535584Y27203D01*
Y41518D01*
X535614Y41548D01*
X538600D01*
X539924Y42872D01*
Y48196D01*
X539996D01*
Y50201D01*
X540141Y50346D01*
X555378D01*
X559832Y45892D01*
Y22648D01*
X558232Y21048D01*
X536000D01*
G37*
G36*
G01X526887Y47845D02*
X531312Y43420D01*
X533668D01*
X534206Y42882D01*
Y27614D01*
X527911D01*
X526752Y28772D01*
Y29533D01*
X526024Y30262D01*
Y30632D01*
X525654D01*
X525599Y30686D01*
X519553D01*
X519529Y30662D01*
X518383D01*
X518348Y30698D01*
X516694D01*
X515853Y31538D01*
Y47163D01*
X516585Y47895D01*
X526505D01*
X526528Y47890D01*
G03X526811Y47849I370J1558D01*
G01X526887Y47845D01*
G37*
G36*
G01X579110Y188976D02*
G02X559273Y177976I-12969J0D01*
G01X554772D01*
Y185972D01*
X562179D01*
G03X571114Y188976I3962J3004D01*
G01Y294875D01*
G02X571834Y295115I400J0D01*
G03X579110Y289124I15962J11971D01*
G01Y188976D01*
G37*
G36*
G01X603269Y41681D02*
X602900Y42050D01*
Y43816D01*
X602708D01*
Y47911D01*
X603054Y48257D01*
X609035D01*
X609271Y48021D01*
Y45784D01*
X609008D01*
Y42182D01*
X609108D01*
Y41888D01*
X608901Y41681D01*
X603269D01*
G37*
G36*
G01X607156Y21024D02*
X606947Y21233D01*
Y35523D01*
X606859Y35611D01*
Y40076D01*
X607228Y40445D01*
X609108D01*
Y40212D01*
X610758D01*
X618504Y32467D01*
Y28269D01*
X618229Y27994D01*
X613434D01*
X613352Y27912D01*
Y21305D01*
X613071Y21024D01*
X607156D01*
G37*
G36*
G01X618047Y60707D02*
X616697Y62057D01*
Y65356D01*
X616698D01*
Y81558D01*
X618842Y83702D01*
X628942D01*
X631347Y81297D01*
Y65912D01*
X630481D01*
G03X629318Y65412I-1J-1601D01*
G01X628799D01*
X625985Y62598D01*
X625938Y62583D01*
G03X624285Y60855I762J-2383D01*
G01X624245Y60707D01*
X618047D01*
G37*
G36*
G01X676647Y37307D02*
X675849Y36509D01*
X675348D01*
Y37208D01*
X671946D01*
Y36510D01*
X644040Y36514D01*
X643086D01*
X641400Y38200D01*
Y47253D01*
X648447Y54300D01*
Y64614D01*
X649252Y65419D01*
X671531D01*
X672897Y64053D01*
Y44857D01*
X676647Y41107D01*
Y37307D01*
G37*
G36*
G01X623283Y47950D02*
X628969Y53636D01*
Y59070D01*
X629310Y59411D01*
X633209D01*
X633743Y58877D01*
Y53414D01*
X635047Y52110D01*
Y34767D01*
X633616Y33336D01*
X619650D01*
X611754Y41232D01*
X611438D01*
X611024Y41646D01*
X610506D01*
Y46578D01*
X610906D01*
X610961Y46532D01*
G03X612110Y46118I1149J1387D01*
G01X616636D01*
X618468Y47950D01*
X623283D01*
G37*
G36*
G01X606405Y49468D02*
Y57869D01*
X607547Y59010D01*
Y72507D01*
X606347Y73707D01*
X602747D01*
X601004Y75450D01*
Y81467D01*
X602004Y82467D01*
X614504D01*
X615496Y81476D01*
Y64305D01*
X615490Y64282D01*
G03X615446Y63907I1557J-373D01*
G01Y62307D01*
G03X615490Y61932I1601J-2D01*
G01X615496Y61909D01*
Y61559D01*
X615504Y61551D01*
Y54967D01*
X610006Y49468D01*
X606405D01*
G37*
G36*
G01X588138Y67216D02*
X586769Y68585D01*
Y79273D01*
X587954Y80458D01*
X597142D01*
X597458Y80142D01*
Y74008D01*
X600723Y70743D01*
Y67216D01*
X588138D01*
G37*
G36*
G01X571114Y319299D02*
Y465244D01*
G02X571888Y465386I400J0D01*
G03X579110Y456095I18663J7055D01*
G01Y325050D01*
G03X571834Y319059I8686J-17962D01*
G02X571114Y319299I-320J240D01*
G37*
G36*
G01X652547Y23107D02*
X651547Y24107D01*
Y34107D01*
X652740Y35300D01*
X670654D01*
X670947Y35007D01*
Y23987D01*
X670067Y23107D01*
X652547D01*
G37*
G36*
G01X671682Y476098D02*
X669700Y478080D01*
Y497700D01*
X670200Y498200D01*
Y504400D01*
X673400D01*
X673600Y504200D01*
Y497200D01*
X674100Y496700D01*
X679500D01*
X680100Y497300D01*
Y500771D01*
X680111Y500803D01*
G03X680192Y501279I-1371J478D01*
G01Y504392D01*
X680200Y504400D01*
X687300D01*
X687400Y504300D01*
Y496500D01*
X688200Y495700D01*
Y478359D01*
X685939Y476098D01*
X671682D01*
G37*
G36*
G01X661900Y517600D02*
X660800Y518700D01*
Y532162D01*
X661444Y532806D01*
X668300D01*
Y517900D01*
X668000Y517600D01*
X661900D01*
G37*
G36*
G01X769827Y486502D02*
X768300Y488029D01*
Y504300D01*
X768400Y504400D01*
X771800D01*
X771900Y504300D01*
Y497500D01*
X772600Y496800D01*
X778000D01*
X778500Y497300D01*
Y500708D01*
X778514Y500743D01*
G03X778616Y501279I-1349J534D01*
G01Y504216D01*
X778700Y504300D01*
X785700D01*
Y497900D01*
X785800Y497800D01*
Y487927D01*
X784375Y486502D01*
X769827D01*
G37*
G36*
G01X742352Y491085D02*
X735480D01*
X734666Y491899D01*
Y494366D01*
X737175Y496875D01*
Y504200D01*
X737275Y504300D01*
X742600D01*
X743200Y503700D01*
Y491933D01*
X742352Y491085D01*
G37*
G36*
G01X763735Y536890D02*
X763741Y536817D01*
G03X765995Y534808I2194J192D01*
G01X766081Y534810D01*
X766856Y534036D01*
Y531004D01*
G03X767200Y530065I1451J-1D01*
G01Y518900D01*
X766900Y518600D01*
X760800D01*
X759700Y519700D01*
Y530544D01*
X757073Y533171D01*
Y536162D01*
X758176Y537265D01*
X763360D01*
X763735Y536890D01*
G37*
G36*
G01X739900Y521700D02*
X738500Y523100D01*
Y526752D01*
X738612D01*
Y535256D01*
X738244D01*
X737600Y535900D01*
Y537100D01*
X738100Y537600D01*
X750200D01*
X751100Y536700D01*
Y522800D01*
X750000Y521700D01*
X739900D01*
G37*
G36*
G01X874919Y57720D02*
X850214Y82425D01*
Y118225D01*
X853112Y121123D01*
X869849D01*
X871865Y119107D01*
Y80013D01*
X878670Y73208D01*
Y73062D01*
X878816D01*
X880699Y71179D01*
X901871D01*
X902059Y70991D01*
Y60329D01*
X899450Y57720D01*
X874919D01*
G37*
G36*
G01X851364Y195106D02*
X854339Y198081D01*
X867820D01*
Y197506D01*
X881003D01*
Y196610D01*
X881103Y196510D01*
X889053D01*
X889918Y195645D01*
Y185781D01*
X889247Y185110D01*
X886403D01*
X886379Y185134D01*
X882479D01*
X882427Y185081D01*
X881206D01*
Y185414D01*
X868619D01*
X868287Y185081D01*
X854427D01*
X851364Y188144D01*
Y190862D01*
X851570D01*
Y194266D01*
X851364D01*
Y195106D01*
G37*
G36*
G01X839492Y187435D02*
X839125Y187802D01*
Y213325D01*
X839328Y213528D01*
X849828D01*
X850118Y213238D01*
Y212968D01*
X850112Y212944D01*
G03X850066Y212564I1556J-381D01*
G01Y211164D01*
G03X850112Y210784I1602J1D01*
G01X850118Y210760D01*
Y208968D01*
X850112Y208944D01*
G03X850066Y208564I1556J-381D01*
G01Y207164D01*
G03X850112Y206784I1602J1D01*
G01X850118Y206760D01*
Y204968D01*
X850112Y204944D01*
G03X850066Y204564I1556J-381D01*
G01Y203164D01*
G03X850118Y202761I1602J2D01*
G01Y202714D01*
X848992Y201588D01*
Y200362D01*
X848987Y200341D01*
G03Y199387I2150J-477D01*
G01X848992Y199366D01*
Y194266D01*
X848966D01*
Y190862D01*
X848992D01*
Y187935D01*
X848492Y187435D01*
X839492D01*
G37*
G36*
G01X889902Y267789D02*
X857932D01*
X855782Y269939D01*
Y323388D01*
X862008Y329614D01*
X887739D01*
X890916Y326437D01*
Y268803D01*
X889902Y267789D01*
G37*
G36*
G01X867593Y347944D02*
X867576Y347962D01*
X858670D01*
X857401Y349231D01*
Y361743D01*
X858927Y363269D01*
X864002D01*
X865949Y365216D01*
Y367025D01*
G03Y370919I-1029J1947D01*
G01Y375128D01*
X866449Y375628D01*
X877725D01*
X880981Y372372D01*
X882342D01*
X885954Y368760D01*
X889774D01*
G03X889839Y368758I82J1599D01*
G01X891439D01*
G03X891504Y368760I-17J1601D01*
G01X892988D01*
X894033Y367715D01*
Y349973D01*
X892004Y347944D01*
X867593D01*
G37*
G36*
G01X854336Y377069D02*
X853733Y377672D01*
Y389169D01*
X854204Y389640D01*
X858072D01*
Y390069D01*
X862343D01*
Y389640D01*
X877673D01*
Y388598D01*
X877773Y388498D01*
X878773D01*
X882066Y385205D01*
X885907D01*
X886866Y384246D01*
Y378007D01*
X885957Y377098D01*
X883073D01*
X883049Y377122D01*
X879149D01*
X879097Y377069D01*
X877759D01*
Y377158D01*
X864312D01*
Y377069D01*
X854336D01*
G37*
G36*
G01X837051Y381106D02*
X836351Y381806D01*
Y406177D01*
X836951Y406777D01*
X844980D01*
X846551Y405206D01*
Y394406D01*
X845251Y393106D01*
Y381606D01*
X844751Y381106D01*
X839510D01*
X839500Y381107D01*
G03X839327Y381116I-170J-1592D01*
G01X837927D01*
G03X837754Y381107I-3J-1601D01*
G01X837744Y381106D01*
X837051D01*
G37*
G36*
G01X833681Y491527D02*
X832799Y492409D01*
Y494199D01*
X835400Y496800D01*
Y497028D01*
X836054D01*
Y504500D01*
X841300D01*
X841600Y504200D01*
Y492409D01*
X840718Y491527D01*
X833681D01*
G37*
G36*
G01X847800Y522500D02*
X837300D01*
X836600Y523200D01*
Y534700D01*
X836100Y535200D01*
Y537250D01*
X836600Y537750D01*
X846600D01*
X847800Y536550D01*
Y522500D01*
G37*
G36*
G01X905422Y73714D02*
X880428D01*
X873807Y80335D01*
Y136363D01*
X875358Y137914D01*
X903706D01*
X905752Y135868D01*
Y74044D01*
X905422Y73714D01*
G37*
G36*
G01X898990Y196779D02*
X898935Y196834D01*
X893219D01*
X892122Y197932D01*
X892024Y198030D01*
Y205134D01*
X890724Y206434D01*
Y220467D01*
G02X891112Y220867I400J0D01*
G03X893178Y221998I-81J2601D01*
G01X893884D01*
G03X898178I2147J1470D01*
G01X906118D01*
X907102Y221014D01*
Y219741D01*
X907096Y219735D01*
Y200168D01*
X903707Y196779D01*
X898990D01*
G37*
G36*
G01X880005Y183514D02*
Y183427D01*
X880760Y182672D01*
X889659D01*
X889667Y182680D01*
X889984D01*
X891837Y180827D01*
X892015D01*
X892073Y180772D01*
G03X893174Y180334I1100J1163D01*
G01X894774D01*
G03X895325Y180431I2J1601D01*
G01X895445Y180475D01*
X896993Y178927D01*
Y155977D01*
X893957Y152941D01*
X872670D01*
X872614Y152998D01*
X867675D01*
X864664Y156009D01*
Y166497D01*
X868617Y170450D01*
Y170784D01*
G03X869354Y174162I-964J1980D01*
G01Y181622D01*
G03X868818Y182862I-1702J0D01*
G01X868754Y182922D01*
Y183514D01*
X880005D01*
G37*
G36*
G01X884539Y198364D02*
X884068Y198835D01*
X881774D01*
Y199016D01*
X881367D01*
X881101Y199282D01*
X869118D01*
X868900Y199500D01*
Y199748D01*
X868948Y199804D01*
G03X869354Y200908I-1295J1103D01*
G01Y208310D01*
G03X869670Y209264I-1286J955D01*
G01Y211864D01*
G03X868985Y213177I-1601J0D01*
G01X868900Y213236D01*
Y213466D01*
X868948Y213522D01*
G03X869332Y214562I-1218J1041D01*
G01Y215962D01*
G03X868900Y217056I-1601J0D01*
G01Y218715D01*
X870981Y220796D01*
X888553D01*
X889392Y219957D01*
Y205640D01*
X889640Y205392D01*
Y205184D01*
X889848D01*
X890822Y204210D01*
Y198518D01*
X890668Y198364D01*
X884539D01*
G37*
G36*
G01X904212Y267610D02*
X894483D01*
X893218Y268875D01*
Y317039D01*
X894676Y318497D01*
X904406D01*
X905506Y317397D01*
Y271347D01*
X905504Y271345D01*
Y268902D01*
X904212Y267610D01*
G37*
G36*
G01X875118Y403322D02*
X873060Y405380D01*
Y409500D01*
X874560Y411000D01*
X878200D01*
X879600Y412400D01*
X904668D01*
X905023Y412045D01*
Y404319D01*
X904026Y403322D01*
X879323D01*
G03X879239Y403324I-80J-1599D01*
G01X877639D01*
G03X877555Y403322I-4J-1601D01*
G01X875118D01*
G37*
G36*
G01X903276Y368179D02*
X896373D01*
X894724Y369828D01*
Y385294D01*
X896881Y387451D01*
X903722D01*
X904526Y386647D01*
Y369429D01*
X903276Y368179D01*
G37*
G36*
G01X902900Y402120D02*
X904756Y400265D01*
Y389810D01*
X903628Y388682D01*
X896099D01*
X893880Y386463D01*
X883118D01*
X878272Y391309D01*
X866540D01*
X865969Y391880D01*
Y400935D01*
X867157Y402123D01*
X874618D01*
X874620Y402120D01*
X902900D01*
G37*
%LPC*%
G75*
G54D137*
X339331Y91929D03*
G54D138*
X346457Y84567D03*
G54D136*
X79968Y505366D03*
X82168D03*
X74273Y505379D03*
X76473D03*
X68800Y505500D03*
X71000D03*
X85573D03*
X32165Y531538D03*
Y533738D03*
X32158Y537154D03*
Y539354D03*
X32258Y542781D03*
Y544981D03*
X32000Y548400D03*
Y550600D03*
X32187Y554053D03*
Y556253D03*
X60354Y638850D03*
Y641050D03*
X60084Y642700D03*
Y645100D03*
X60246Y646750D03*
Y648950D03*
X65954Y638850D03*
X84200Y639716D03*
X86600D03*
X65954Y641050D03*
X66084Y642700D03*
X80584Y666700D03*
X82984D03*
X80584Y672700D03*
X82984D03*
X130200Y622600D03*
X133600D03*
X134800Y624100D03*
X120700Y629900D03*
X134800Y630100D03*
X137200D03*
X130200Y631600D03*
X133600D03*
X125600Y636000D03*
X129000D03*
X120600Y637700D03*
X121900D03*
X124300D03*
X120600Y643700D03*
X121900D03*
X124300D03*
X125600Y645000D03*
X136549Y686615D03*
Y688815D03*
X120349Y689747D03*
X122549D03*
X112249Y692547D03*
X114449D03*
X116249D03*
X85650Y725450D03*
Y719950D03*
X97750D03*
Y725450D03*
X156796Y514819D03*
X158996D03*
X160802Y514849D03*
X177676Y637568D03*
X179876D03*
X181776D03*
X183976D03*
X185876D03*
X188076D03*
X189976Y637698D03*
X192176D03*
X171700Y638300D03*
X173600D03*
X175800D03*
X217423Y650846D03*
X213623Y650996D03*
X215823D03*
X224200Y711800D03*
X226600D03*
X148617Y738848D03*
Y741248D03*
X224200Y717800D03*
X226600D03*
X310504Y710920D03*
X312904D03*
X338334Y119612D03*
X341734D03*
X343334D03*
X346734D03*
X330750Y121050D03*
X336250D03*
X343334Y121112D03*
X346734D03*
X330750Y108950D03*
X352482Y188578D03*
Y190978D03*
X352282Y192478D03*
X346482Y188578D03*
Y190978D03*
X346682Y192478D03*
Y194678D03*
X320800Y640800D03*
X323200D03*
X300870Y611150D03*
Y613550D03*
X300900Y615284D03*
Y617484D03*
X301953Y619450D03*
Y621650D03*
X306870Y611150D03*
X316400Y611600D03*
X318800D03*
X306870Y613550D03*
X306500Y615284D03*
X320800Y646800D03*
X290218Y683053D03*
Y685253D03*
X290004Y686920D03*
Y689320D03*
X290282Y690847D03*
Y693047D03*
X313520Y683020D03*
X315920D03*
X295818Y683053D03*
Y685253D03*
X296004Y686920D03*
X310504Y716920D03*
X368200Y120700D03*
X370600D03*
X373783Y185653D03*
X375304Y196091D03*
Y198491D03*
X386211Y578231D03*
X379900Y579300D03*
X381900D03*
X384100D03*
X394000Y590200D03*
Y592100D03*
X394100Y602400D03*
Y604300D03*
X393736Y627480D03*
Y629680D03*
X393700Y636800D03*
X494500Y39200D03*
X494300Y40900D03*
Y43100D03*
X497535Y45757D03*
Y49157D03*
X441485Y20857D03*
Y23057D03*
X441585Y25057D03*
Y27257D03*
Y29357D03*
Y31557D03*
X441335Y33157D03*
X433085Y36957D03*
Y39157D03*
X431557Y40788D03*
Y44188D03*
X431555Y45444D03*
Y48844D03*
X431546Y50100D03*
Y53500D03*
X502681Y29699D03*
X548000Y60000D03*
Y62400D03*
X537408Y67541D03*
X540808D03*
X537408Y70941D03*
X540808D03*
X507355Y20702D03*
X506081Y20699D03*
X502681D03*
X554000Y60000D03*
Y62400D03*
X537408Y76541D03*
X540808D03*
X510755Y29702D03*
X610747Y28607D03*
Y32007D03*
X619047Y61907D03*
Y64307D03*
X668247Y38907D03*
X670647D03*
X621337Y35726D03*
X623737D03*
X630081Y55711D03*
X613047Y61907D03*
Y64307D03*
X597247Y70707D03*
X668247Y32907D03*
X841068Y189714D03*
X843268D03*
X847868Y202764D03*
Y204964D03*
Y206764D03*
Y208964D03*
Y210764D03*
X889439Y366360D03*
X891839D03*
X837527Y383315D03*
X839727D03*
X844360Y394898D03*
Y397098D03*
Y398898D03*
Y401098D03*
Y402898D03*
Y405098D03*
X892774Y177935D03*
X895174D03*
X877239Y405723D03*
X879639D03*
X896847Y382107D03*
X902347D03*
Y386607D03*
X896847Y389707D03*
X902347D03*
X896847Y394207D03*
X902347D03*
X877239Y399723D03*
X879639D03*
%LPD*%
G75*
G54D100*
X478050Y42290D03*
Y28510D03*
X457950D03*
Y42290D03*
X612110Y47920D03*
Y42014D03*
X599898D03*
Y47920D03*
G54D110*
X612060Y45951D03*
Y43983D03*
X599948D03*
Y45951D03*
G54D101*
X477750Y40321D03*
Y38353D03*
Y36384D03*
Y34416D03*
Y32447D03*
Y30479D03*
X458250D03*
Y32447D03*
Y34416D03*
Y36384D03*
Y38353D03*
Y40321D03*
G54D111*
X588647Y35057D03*
G54D102*
X468000Y35400D03*
G54D120*
X801024Y24409D03*
X811024D03*
X821024D03*
G54D130*
G01X157874Y562992D02*
X157871D01*
X156820Y561941D01*
G02X155176Y561260I-1644J1643D01*
G01X158795Y564566D02*
G03X159904Y565026I0J1567D01*
G01X161021Y566142D01*
X161023D01*
G01X157874Y569291D02*
X157721D01*
G03X156695Y568866I0J-1451D01*
G01X156195Y568366D01*
X156020Y568190D01*
G02X154995Y567766I-1025J1027D01*
G01X673647Y36157D02*
Y37447D01*
G01Y35657D02*
Y33107D01*
G01X904262Y71265D02*
Y69540D01*
G01Y71765D02*
Y74472D01*
G54D121*
X869622Y191265D03*
X866114Y383399D03*
G54D10*
X38500Y49800D03*
X48200Y675584D03*
X78268Y60055D03*
X104000Y478800D03*
X108500Y487300D03*
X104000D03*
X108277Y570651D03*
X111200Y709900D03*
X86028Y689739D03*
X81928Y689839D03*
X174588Y489713D03*
X187167Y502984D03*
X198700Y516900D03*
X203500D03*
X212600Y517000D03*
X141914Y519838D03*
X182648Y503054D03*
X204100Y638000D03*
X142572Y633732D03*
X150872D03*
X166500Y633800D03*
X157458Y633832D03*
X145279Y619170D03*
X172700Y622700D03*
X176800D03*
X180985D03*
X185085D03*
X189185D03*
X193285D03*
X149400Y623200D03*
X154300Y703515D03*
X168047Y705075D03*
X151749Y695715D03*
X164249D03*
X210123Y655596D03*
X267514Y540585D03*
X243700Y552100D03*
X229342Y514955D03*
X223400Y638000D03*
X238000Y621800D03*
X234000D03*
X221900Y623700D03*
X229952Y626430D03*
X225900Y623700D03*
X251900Y613400D03*
X243900D03*
X262823Y624696D03*
X236000Y639200D03*
X225984Y659043D03*
X258431Y704824D03*
X246700Y675900D03*
X247500Y702300D03*
X214723Y652096D03*
X343582Y178478D03*
X347882Y271078D03*
X346819Y520675D03*
X350400Y528500D03*
X341226Y528509D03*
X334827Y517153D03*
X304617Y589881D03*
X299000Y658100D03*
X289612Y661529D03*
X291700Y730200D03*
X287620Y730220D03*
X374883Y181153D03*
X359481Y484466D03*
X384300Y548400D03*
X361120Y585686D03*
X374600Y583400D03*
X464342Y53858D03*
X468400Y61300D03*
X472700Y61200D03*
X443489Y42401D03*
X594541Y29581D03*
X590347Y57307D03*
X703300Y21800D03*
X713200Y390800D03*
X712851Y474882D03*
X712000Y435400D03*
X718300Y390800D03*
X725200Y435400D03*
X754800Y527000D03*
X854596Y159135D03*
X841625Y177777D03*
X846077Y152224D03*
X838627Y378815D03*
X846456Y354057D03*
X834984Y371069D03*
X796100Y389800D03*
X801200D03*
X811099Y473779D03*
X794900Y434400D03*
X808100D03*
G54D103*
X530998Y64511D03*
Y78351D03*
G54D112*
X588647Y32557D03*
G54D131*
G01X34000Y48500D02*
Y44000D01*
X38386Y39614D01*
Y24606D01*
G01X34000Y48500D02*
X37250D01*
X38500Y49750D01*
G01D02*
X41750D01*
X43000Y48500D01*
G01X46500D02*
X43000D01*
G01X67852Y539219D02*
X69427Y540794D01*
G01X71002Y545518D02*
X63507D01*
X62573Y544584D01*
X60344D01*
X59844Y544084D01*
Y541135D01*
X59344Y540635D01*
X58344D01*
X57844Y541135D01*
Y544084D01*
X57344Y544584D01*
X55920D01*
X55415Y544079D01*
Y542104D01*
X54359Y541048D01*
X41339D01*
X40756Y541631D01*
Y543876D01*
G01D02*
X40751Y543881D01*
X36808D01*
G01X69427Y562841D02*
Y562842D01*
X67853Y564416D01*
G01X69427Y553392D02*
X68077Y552042D01*
X64158D01*
X62809Y553391D01*
X62772D01*
X58147Y558016D01*
X51105D01*
X50605Y558516D01*
Y559924D01*
X50105Y560424D01*
X49105D01*
X48605Y559924D01*
Y558516D01*
X48105Y558016D01*
X47105D01*
X46605Y558516D01*
Y559924D01*
X46105Y560424D01*
X45105D01*
X44605Y559924D01*
Y558516D01*
X44105Y558016D01*
X43600D01*
X40737Y555153D01*
G01X67853Y554967D02*
X69427Y553393D01*
Y553392D01*
G01X36737Y555153D02*
X40737D01*
G01X40756Y538249D02*
Y536211D01*
X41468Y535499D01*
X56210D01*
X57345Y536634D01*
Y537684D01*
X57931Y538270D01*
X58759D01*
X59345Y537684D01*
Y533965D01*
X59931Y533379D01*
X60759D01*
X61345Y533965D01*
Y538481D01*
X62692Y539828D01*
Y543284D01*
X63692Y544284D01*
X65937D01*
X66278Y543943D01*
G01X36708Y538254D02*
X40751D01*
X40756Y538249D01*
G01X67853Y542368D02*
X66278Y543943D01*
G01X40656Y532622D02*
X38420D01*
X38404Y532638D01*
X36715D01*
G01X72577Y537644D02*
X64178Y529245D01*
X51040D01*
X49041Y527246D01*
X42254D01*
X40656Y528844D01*
Y532622D01*
G01X69427Y550242D02*
X68188D01*
X66789Y548843D01*
X60909D01*
X59777Y547711D01*
X58009D01*
X57440Y548280D01*
Y552121D01*
X56940Y552621D01*
X55940D01*
X55440Y552121D01*
Y547200D01*
X54940Y546700D01*
X41450D01*
X40550Y547600D01*
Y549500D01*
G01X36550D02*
X40550D01*
G01X85630Y34449D02*
X82080D01*
X82074Y34455D01*
X76452D01*
X73768Y37139D01*
Y58755D01*
G01X78268Y60005D02*
X77018Y58755D01*
X73768D01*
G01X82768D02*
X81518Y60005D01*
X78268D01*
G01X86268Y58755D02*
X82768D01*
G01X108500Y487250D02*
Y482250D01*
G01X124290Y460300D02*
X130259D01*
X132598Y462639D01*
X132777D01*
G01X154334Y465100D02*
X154134Y465300D01*
X124290D01*
G01X104000Y482250D02*
Y487250D01*
G01X108500Y490750D02*
X114095D01*
X118645Y495300D01*
X123586D01*
G01X104000Y490750D02*
X108500D01*
G01X104000D02*
X100600D01*
G01X135262Y475726D02*
Y491109D01*
X152585Y508432D01*
Y515485D01*
X154800Y517700D01*
Y520951D01*
X158693Y524844D01*
Y528636D01*
X165662Y535605D01*
Y539283D01*
X167323Y540944D01*
Y540945D01*
G01X72577Y543943D02*
X72578D01*
X74151Y545516D01*
G01X86750Y542368D02*
X85175Y543943D01*
G01X126337Y554085D02*
X125752Y554670D01*
X112314D01*
X111814Y554170D01*
Y551610D01*
X112314Y551110D01*
X128323D01*
X128823Y551610D01*
Y553276D01*
X130694Y555147D01*
Y555853D01*
X129358Y557190D01*
Y557896D01*
X130067Y558605D01*
X130773D01*
X132109Y557268D01*
X132815D01*
X138557Y563010D01*
X143719D01*
X143737Y562992D01*
X154724D01*
G01X72577Y550242D02*
X74092Y551757D01*
X74498D01*
G01X155176Y561260D02*
X149591D01*
X149341Y561010D01*
X141994D01*
X139120Y558136D01*
X138412D01*
X137898Y558650D01*
X137190D01*
X136483Y557943D01*
Y557235D01*
X136997Y556721D01*
Y556013D01*
X136290Y555306D01*
X135582D01*
X135068Y555820D01*
X134360D01*
X133653Y555113D01*
Y554405D01*
X134167Y553891D01*
Y553183D01*
X133460Y552476D01*
X132752D01*
X132238Y552990D01*
X131530D01*
X130823Y552283D01*
Y551575D01*
X131337Y551061D01*
Y550353D01*
X130311Y549327D01*
Y546700D01*
G01X71002Y539219D02*
X69427Y537644D01*
G01X85175Y550242D02*
X84838Y549905D01*
X82415D01*
X81276Y548766D01*
G01X119605Y548705D02*
Y544208D01*
X119105Y543708D01*
X116440D01*
X115940Y543208D01*
Y542208D01*
X116440Y541708D01*
X119105D01*
X119605Y541208D01*
Y539224D01*
X120239Y538590D01*
X121772D01*
X122272Y539090D01*
Y548550D01*
X122772Y549050D01*
X123772D01*
X124272Y548550D01*
Y545860D01*
X124772Y545360D01*
X125772D01*
X126272Y545860D01*
Y548380D01*
X126772Y548880D01*
X127772D01*
X128272Y548380D01*
Y545057D01*
X129149Y544180D01*
X130620D01*
X132311Y545871D01*
Y548498D01*
X141943Y558130D01*
X153920D01*
X154724Y558934D01*
Y559842D01*
G01X88325Y537644D02*
X86751Y539218D01*
X86750D01*
G01X72577Y540794D02*
X74076Y539295D01*
Y535966D01*
G01X83600Y545518D02*
X85175Y547093D01*
G01X72577D02*
X72731Y547247D01*
X75095D01*
X75860Y546482D01*
Y542550D01*
X75508Y542198D01*
G01X88325Y543943D02*
Y543944D01*
X89899Y545518D01*
G01X71002Y542368D02*
X69427Y543943D01*
G01X154724Y556693D02*
X143501D01*
X140993Y554185D01*
X140827D01*
X134401Y547759D01*
Y545132D01*
X129169Y539900D01*
X125720D01*
X125219Y540401D01*
Y542539D01*
X125880Y543200D01*
X127300D01*
G01X157874Y556693D02*
X157217Y556037D01*
G02X154995Y555116I-2222J2220D01*
G01X144753D01*
X141822Y552185D01*
X141656D01*
X136401Y546930D01*
Y544303D01*
X129668Y537570D01*
X125290D01*
X124320Y536600D01*
X122371D01*
X122151Y536380D01*
X114700D01*
X113980Y537100D01*
Y541715D01*
X113480Y542215D01*
X112480D01*
X111980Y541715D01*
Y535700D01*
X111480Y535200D01*
X110480D01*
X109980Y535700D01*
Y543715D01*
X110480Y544215D01*
X113480D01*
X113980Y544715D01*
Y545800D01*
X114480Y546300D01*
X117200D01*
G01X88325Y540794D02*
X89899Y539220D01*
Y539218D01*
G01X83600Y539219D02*
X85175Y540794D01*
G01X71002Y545518D02*
X69427Y547093D01*
G01X101113Y519327D02*
Y515363D01*
X101100Y515350D01*
G01X86750Y545518D02*
X88325Y547093D01*
G01X122600Y557480D02*
X107900D01*
X107400Y557980D01*
Y560330D01*
X107900Y560830D01*
X133548D01*
X137728Y565010D01*
X143313D01*
X143757Y564566D01*
X158795D01*
G01X88325Y547093D02*
X89975Y548743D01*
X95568D01*
X103000Y541311D01*
Y521214D01*
X101113Y519327D01*
G01X81032Y514027D02*
Y509952D01*
X81068Y509916D01*
G01X81032Y514027D02*
X83800Y516795D01*
Y524700D01*
X81100Y527400D01*
Y546200D01*
X83566Y548666D01*
X86749D01*
X88325Y550242D01*
G01D02*
X89849Y551766D01*
X93990D01*
X94816Y552592D01*
X101960D01*
X102460Y553092D01*
Y556330D01*
X101960Y556830D01*
X97690D01*
X97190Y557330D01*
Y558330D01*
X97690Y558830D01*
X104720D01*
X105220Y559330D01*
Y560330D01*
X104720Y560830D01*
X97000D01*
X96563Y561267D01*
Y566460D01*
X97063Y566960D01*
X98063D01*
X98563Y566460D01*
Y563330D01*
X99063Y562830D01*
X100063D01*
X100563Y563330D01*
Y566460D01*
X101063Y566960D01*
X102063D01*
X102563Y566460D01*
Y563330D01*
X103063Y562830D01*
X132719D01*
X136899Y567010D01*
X145456D01*
X145900Y566566D01*
X154300D01*
X154724Y566142D01*
G01X69427Y556542D02*
X71002Y558117D01*
G01X85175Y553392D02*
X83600Y551817D01*
G01X75405Y514027D02*
Y509961D01*
X75373Y509929D01*
G01X154995Y567766D02*
X146800D01*
X145556Y569010D01*
X136023D01*
X134352Y567339D01*
Y567292D01*
X131930Y564870D01*
X123021D01*
X122521Y565370D01*
Y567260D01*
X122021Y567760D01*
X121021D01*
X120521Y567260D01*
Y565370D01*
X120021Y564870D01*
X105130D01*
X104630Y565370D01*
Y567240D01*
X105130Y567740D01*
X117310D01*
X117400Y567650D01*
G01X83600Y551817D02*
X83599Y551816D01*
X81992D01*
X79626Y549450D01*
Y547373D01*
X79900Y547099D01*
Y546276D01*
X79926Y546250D01*
Y544882D01*
X79900Y544856D01*
Y527745D01*
X78155Y526000D01*
Y516777D01*
X75405Y514027D01*
G01X69427Y572290D02*
X70866Y573729D01*
X73400D01*
X73891Y574220D01*
X75799D01*
X76988Y573031D01*
Y564909D01*
X77558Y564339D01*
X79698D01*
X80268Y564909D01*
Y587123D01*
X82261Y589116D01*
X95740D01*
X96936Y587920D01*
X106234D01*
X108736Y585418D01*
X138675D01*
X141242Y582851D01*
X141339D01*
X142390Y581800D01*
X154634D01*
X154724Y581890D01*
G01X69427Y565990D02*
X69428D01*
X71002Y564416D01*
Y564396D01*
G01X72577Y562841D02*
X71002Y561266D01*
G01X85175Y562841D02*
X85174D01*
X83600Y564415D01*
G01X88325Y562841D02*
X88324D01*
X86750Y564415D01*
G01X72577Y559691D02*
Y560746D01*
X75066Y563235D01*
G01X85175Y559691D02*
X83601Y561265D01*
X83600D01*
G01X72577Y556542D02*
X71002Y554967D01*
G01X88325Y553392D02*
X87968Y553035D01*
Y553033D01*
X86750Y551815D01*
G01X136850Y529700D02*
X135000D01*
X133800Y528500D01*
G01X93614Y507352D02*
X102549D01*
X102601Y507300D01*
G01X93614Y501352D02*
Y496474D01*
X93531Y496391D01*
G01X130450Y534600D02*
Y530300D01*
G01D02*
X132771D01*
X134571Y532100D01*
X139000D01*
X142561Y535661D01*
Y542243D01*
X148912Y548594D01*
X156074D01*
X157874Y550394D01*
G01X126950Y534600D02*
X123200D01*
G01X69778Y514027D02*
X72528Y516777D01*
Y523558D01*
X77728Y528758D01*
Y529585D01*
X77140Y530172D01*
X76312D01*
X74638Y528498D01*
X73810D01*
X73222Y529085D01*
Y529912D01*
X78276Y534966D01*
Y545566D01*
G01X69778Y514027D02*
Y510172D01*
X69900Y510050D01*
G01X72577Y553392D02*
X73864Y554679D01*
X76594D01*
X78276Y552997D01*
Y545566D01*
G01X91474Y543943D02*
X91820D01*
X93744Y542019D01*
G01X86659Y514027D02*
Y510064D01*
X86673Y510050D01*
G01X92000Y513950D02*
X86736D01*
X86659Y514027D01*
G01X93744Y542019D02*
X96293D01*
X99111Y539201D01*
Y530693D01*
X95036Y526618D01*
Y515196D01*
X93790Y513950D01*
X92000D01*
G01X154724Y553543D02*
X145843D01*
X138401Y546101D01*
Y543210D01*
X133554Y538363D01*
Y537374D01*
G01X69427Y550242D02*
X69428D01*
X71002Y548668D01*
G01X125788Y514552D02*
X128252D01*
X131021Y517321D01*
X140229D01*
X142000Y515550D01*
G01X141914Y519788D02*
X136272D01*
X135012Y521048D01*
G01X85175Y572290D02*
X83600Y573865D01*
G01X85175Y569140D02*
Y570165D01*
X85950Y570940D01*
X92330D01*
X93060Y570210D01*
X95560D01*
X96060Y570710D01*
Y572590D01*
X96853Y573383D01*
X102387D01*
X102887Y573883D01*
Y576082D01*
X102886Y576083D01*
X102440Y576530D01*
X96200D01*
X95700Y577030D01*
Y579060D01*
X96340Y579700D01*
X98660D01*
X99750Y580790D01*
Y584540D01*
X100130Y584920D01*
X103255D01*
X103635Y584540D01*
Y581080D01*
X104188Y580527D01*
X106187D01*
X106635Y580975D01*
Y581918D01*
X107135Y582418D01*
X136032D01*
X137432Y581018D01*
Y579130D01*
X137932Y578630D01*
X146236D01*
X146736Y578130D01*
Y576836D01*
X145980Y576080D01*
Y575112D01*
X148052Y573040D01*
X152210D01*
X153236Y574066D01*
X161395D01*
G03X163535Y574953I0J3025D01*
G01X164173Y575590D01*
G01X72577Y578589D02*
X72578D01*
X74152Y580163D01*
G01X85175Y578589D02*
Y578590D01*
X83601Y580164D01*
G01X69427Y578589D02*
Y579828D01*
X70777Y581178D01*
Y590066D01*
X71277Y590566D01*
X73820D01*
X74320Y591066D01*
Y593066D01*
X73820Y593566D01*
X71277D01*
X70777Y594066D01*
Y596797D01*
X77220Y603240D01*
X81010D01*
X83090Y601160D01*
X93620D01*
X100860Y593920D01*
X110828D01*
X113330Y591418D01*
X142484D01*
X143816Y592750D01*
X145743D01*
X147343Y591150D01*
X152750D01*
X154100Y589800D01*
X156263D01*
X157874Y588189D01*
G01X88325Y578589D02*
X89899Y577015D01*
Y577014D01*
G01X72577Y575439D02*
X74151Y577013D01*
X74152D01*
G01X85175Y575439D02*
X86750Y577014D01*
G01X72577Y584888D02*
X72689Y585000D01*
X78260D01*
X78760Y585500D01*
Y591071D01*
X79679Y591990D01*
X88930D01*
X89430Y592490D01*
Y594490D01*
X88930Y594990D01*
X81370D01*
X80870Y595490D01*
Y597490D01*
X81370Y597990D01*
X90331D01*
X96901Y591420D01*
X98179D01*
X98679Y590920D01*
X109585D01*
X112087Y588418D01*
X139918D01*
X142850Y585486D01*
Y585416D01*
X143816Y584450D01*
X143886D01*
X144749Y583587D01*
X154674D01*
X154795Y583466D01*
G02X157361Y582403I0J-3629D01*
G01X157874Y581890D01*
G01X88325Y581738D02*
X89675Y583088D01*
X94229D01*
X95587Y581730D01*
X96570D01*
G01X108277Y570601D02*
X107542Y569866D01*
X97966D01*
X97240Y569140D01*
X91474D01*
G01X124903Y613900D02*
Y610297D01*
X127539Y607661D01*
Y599789D01*
X126750Y599000D01*
G01D02*
X130500D01*
G01X134199Y599062D02*
X130562D01*
X130500Y599000D01*
G01X124793Y617299D02*
X122899D01*
X121853Y616253D01*
Y613818D01*
G01X128800Y611100D02*
X128248D01*
X127300Y612048D01*
Y614200D01*
X126050Y615450D01*
Y616042D01*
X124793Y617299D01*
G01X128800Y611100D02*
X131267D01*
X133227Y613060D01*
G01X136727D02*
X137167Y613500D01*
X140340D01*
X141865Y611975D01*
X143221D01*
G01X135745Y617354D02*
X139846D01*
X140800Y616400D01*
G01X132245Y617354D02*
X130554D01*
X128700Y615500D01*
G01X137699Y599062D02*
X142500D01*
G01X140090Y621027D02*
X143000Y618117D01*
Y616600D01*
X148245Y611355D01*
Y605215D01*
X154123Y599337D01*
X156175D01*
X157874Y597638D01*
G01X106199Y620264D02*
X103098D01*
G01X98537Y601094D02*
X101042Y598589D01*
X104314D01*
X105423Y597480D01*
X113195D01*
X114221Y596454D01*
G01X106199Y599764D02*
X104863Y601100D01*
X102509D01*
G01X106199Y607964D02*
X103717D01*
X103109Y608572D01*
G01X106199Y603864D02*
X104413D01*
X103124Y605153D01*
G01X106199Y612064D02*
X103098D01*
G01X106199Y624364D02*
X103098D01*
G01X154724Y591338D02*
X154162D01*
X149600Y595900D01*
X135300D01*
X134062Y594662D01*
X127263D01*
G01D02*
X119513D01*
X117721Y596454D01*
G01X109699Y599764D02*
X113672Y603737D01*
Y605134D01*
G01X109699Y607964D02*
Y608926D01*
X113512Y612739D01*
Y613401D01*
G01X113426Y609234D02*
Y608343D01*
X109699Y604616D01*
Y603864D01*
G01Y612064D02*
Y614308D01*
X108137Y615870D01*
G01X113400Y621400D02*
X112663D01*
X109699Y624364D01*
G01X113400Y617400D02*
X112563D01*
X109699Y620264D01*
G01X131212Y603311D02*
X132837Y604936D01*
Y608622D01*
X133835Y609620D01*
G01X154724Y594488D02*
X154112Y595100D01*
X153938D01*
X152373Y596665D01*
Y597234D01*
X147007Y602600D01*
X139146D01*
X138473Y603273D01*
G01D02*
X137746Y604000D01*
X135401D01*
X134712Y603311D01*
G01X184924Y489698D02*
X181447D01*
X181200Y489451D01*
G01X161440Y490300D02*
X154732D01*
X152630Y492402D01*
X144287D01*
X140490Y488605D01*
G01X182489Y474031D02*
Y476799D01*
X178720Y480568D01*
X172555D01*
X169252Y483871D01*
G01X171200Y509840D02*
X172803Y508237D01*
Y496696D01*
X174588Y494911D01*
Y493163D01*
G01X162144Y495300D02*
X164429D01*
X170066Y489663D01*
X174588D01*
G01X191400Y502350D02*
Y499600D01*
X190900Y499100D01*
Y486384D01*
X190036Y485520D01*
G01X194411Y485447D02*
X198800Y489836D01*
Y499629D01*
X199850Y500679D01*
Y503300D01*
G01X162144Y460300D02*
X178493D01*
X179013Y459780D01*
G01Y469880D02*
Y474007D01*
X178989Y474031D01*
G01X162144Y470300D02*
X169497D01*
X169917Y469880D01*
X179013D01*
G01X199000Y479500D02*
X205000Y485500D01*
Y498000D01*
X206250Y499250D01*
X212000D01*
G01X170472Y550394D02*
Y550393D01*
X168898Y548819D01*
G01X196100Y524600D02*
Y531927D01*
X201968Y537795D01*
G01X198700Y520350D02*
Y522000D01*
X196100Y524600D01*
G01X165745Y564567D02*
X167320Y566142D01*
X167323D01*
G01X168895Y564567D02*
X170470Y566142D01*
X170472D01*
G01X159449Y561417D02*
X161023Y562991D01*
Y562992D01*
G01X164173D02*
X165748Y561417D01*
G01X170472Y562992D02*
X172047Y561417D01*
G01X162598Y558268D02*
X164172Y559842D01*
X164173D01*
G01X168898Y558268D02*
X167324Y559842D01*
X167323D01*
G01X164173Y556693D02*
X165748Y555118D01*
G01X159449D02*
X161023Y556692D01*
Y556693D01*
G01X190945Y545669D02*
X189370Y544094D01*
G01X202800Y510100D02*
X201250Y511650D01*
Y524550D01*
X200300Y525500D01*
G01D02*
X197750Y528050D01*
Y531667D01*
X203318Y537235D01*
Y539423D01*
X201968Y540773D01*
Y540945D01*
G01Y544094D02*
X203424Y542638D01*
Y540729D01*
X205008Y539145D01*
X205678D01*
X206468Y538355D01*
Y528198D01*
X208000Y526666D01*
Y520500D01*
G01X217134Y521103D02*
Y532078D01*
X211417Y537795D01*
G01X208100Y515200D02*
Y516600D01*
X210650Y519150D01*
Y533303D01*
X208267Y535686D01*
Y537795D01*
G01X173622Y547244D02*
X172047Y545669D01*
G01X173622Y553543D02*
X172047Y551970D01*
G01X159449Y545671D02*
X159450D01*
X161023Y547244D01*
G01X164173D02*
X162599Y545669D01*
G01X165749D02*
X167323Y547243D01*
Y547244D01*
G01X212991Y561419D02*
X212990D01*
X211417Y562992D01*
G01X184646Y548821D02*
X184647D01*
X186220Y550394D01*
G01X184646Y545671D02*
X184647D01*
X186220Y547244D01*
G01X188158Y527500D02*
X185300Y530358D01*
Y531824D01*
X181721Y535403D01*
Y539595D01*
X183071Y540945D01*
G01X188158Y527500D02*
X189350Y526308D01*
Y520700D01*
X190600Y519450D01*
G01X192800Y529100D02*
Y531400D01*
X190017Y534183D01*
X186683D01*
X183071Y537795D01*
G01X194649Y520401D02*
Y522251D01*
X193600Y523300D01*
Y528300D01*
X192800Y529100D01*
G01X184645Y542519D02*
X186220Y544094D01*
G01X179921D02*
X178338Y542511D01*
Y531462D01*
X179013Y530787D01*
Y528910D01*
X179021Y528902D01*
G01X182648Y506504D02*
Y510098D01*
X182964Y510414D01*
G01X179400Y525100D02*
X179021Y525479D01*
Y528902D01*
G01X178469Y521443D02*
Y524169D01*
X179400Y525100D01*
G01X205118Y544094D02*
X205119D01*
X206693Y542520D01*
G01X159449Y542521D02*
X161022Y544094D01*
X161023D01*
G01X173622Y537795D02*
Y536377D01*
X171906Y534661D01*
G01X211417Y544094D02*
Y544093D01*
X212991Y542519D01*
G01X154724Y547244D02*
X152162D01*
X143900Y538982D01*
Y533250D01*
X140350Y529700D01*
G01X156299Y545671D02*
X156301D01*
X157874Y547244D01*
G01X187100Y509600D02*
X187167Y509533D01*
Y506434D01*
G01X190600Y515950D02*
X187100Y512450D01*
Y509600D01*
G01X194649Y516901D02*
Y514000D01*
X195200Y513449D01*
Y513200D01*
G01X167323Y550394D02*
Y550393D01*
X165749Y548819D01*
G01X175197Y545671D02*
X175198D01*
X176771Y547244D01*
G01X162599Y542519D02*
X164173Y544093D01*
Y544094D01*
G01X168898Y542519D02*
X170472Y544093D01*
Y544094D01*
G01X156299Y542521D02*
X156301D01*
X157874Y544094D01*
G01X170380Y520450D02*
X172251Y522321D01*
Y527520D01*
X173175Y528444D01*
G01D02*
X176771Y532040D01*
Y537795D01*
G01X166280Y520450D02*
X169420Y523590D01*
Y526499D01*
G01D02*
Y528119D01*
X174995Y533694D01*
Y539169D01*
X176771Y540945D01*
G01X182474Y520741D02*
X181900Y521315D01*
Y526450D01*
X183350Y527900D01*
G01D02*
Y531650D01*
X179921Y535079D01*
Y537795D01*
G01X181496Y542520D02*
X179921Y540945D01*
G01X186537Y519431D02*
Y521413D01*
X183750Y524200D01*
G01X165572Y529088D02*
X167875Y531391D01*
Y536163D01*
X168800Y537088D01*
Y539273D01*
X170472Y540945D01*
G01X161902Y519399D02*
X161940Y519437D01*
Y525456D01*
X165572Y529088D01*
G01X164173Y537795D02*
Y535389D01*
X157793Y529009D01*
Y527120D01*
X154151Y523478D01*
G01X149742Y515686D02*
X152836Y518780D01*
Y522163D01*
X154151Y523478D01*
G01X160743Y527786D02*
X166975Y534018D01*
Y536542D01*
X167323Y536890D01*
Y537795D01*
G01X157896Y519369D02*
X160309Y521782D01*
Y527352D01*
X160743Y527786D01*
G01X153985Y527761D02*
X155195D01*
X162695Y535261D01*
Y539467D01*
X164173Y540945D01*
G01X149742Y519686D02*
Y522391D01*
X153985Y526634D01*
Y527761D01*
G01X159449Y548821D02*
X159450D01*
X161023Y550394D01*
G01X192519Y544094D02*
X194094Y542519D01*
G01X178469Y517943D02*
Y513731D01*
X178800Y513400D01*
G01X173622Y550394D02*
X172047Y548819D01*
G01X168898Y551969D02*
X170472Y553543D01*
G01X162599Y548821D02*
X162600D01*
X164173Y550394D01*
G01X141914Y523288D02*
Y524240D01*
X144087Y526413D01*
G01X161023Y559842D02*
X162598Y561417D01*
G01X168898Y555119D02*
X170472Y556692D01*
Y556693D01*
G01X181497Y548821D02*
X181498D01*
X183071Y550394D01*
G01X179921Y547244D02*
X179920D01*
X178346Y545670D01*
G01X183071Y547244D02*
X183070D01*
X181497Y545671D01*
G01X162595Y564567D02*
X162596D01*
X164171Y566142D01*
X164173D01*
G01X203542Y551970D02*
X203541D01*
X201968Y553543D01*
G01X174400Y512650D02*
Y509900D01*
X174700Y509600D01*
G01X140517Y537795D02*
Y544817D01*
X144800Y549100D01*
G01X154724Y550394D02*
X154618Y550500D01*
X146200D01*
X144800Y549100D01*
G01X200393Y548819D02*
X198819Y550393D01*
Y550394D01*
G01X208267Y547244D02*
X209842Y545669D01*
G01X208267Y566142D02*
X209842Y564567D01*
G01Y558268D02*
X209841D01*
X208267Y559842D01*
G01X211417Y553543D02*
X211418D01*
X212992Y551969D01*
G01X211417Y550394D02*
X212992Y548819D01*
G01X208267Y562992D02*
X209842Y561417D01*
G01X195500Y502750D02*
X196050Y503300D01*
X199850D01*
G01X200393Y545669D02*
X198819Y547243D01*
Y547244D01*
G01X156000Y496100D02*
Y499900D01*
X165500Y509400D01*
Y514000D01*
X164300Y515200D01*
Y524417D01*
X169981Y530098D01*
Y535265D01*
X172108Y537392D01*
Y539273D01*
X173622Y540787D01*
Y540945D01*
G01X206692Y545671D02*
X208267Y544096D01*
Y544094D01*
G01X229762Y522829D02*
X229041Y523550D01*
X226333D01*
X223743Y526140D01*
Y528316D01*
X222150Y529909D01*
Y533907D01*
X219166Y536891D01*
Y538396D01*
X218317Y539245D01*
X213117D01*
X211417Y540945D01*
G01X156200Y535800D02*
X157874Y537474D01*
Y537795D01*
G01X212150Y495300D02*
X212000Y499250D01*
G01X208267Y550394D02*
X209842Y548819D01*
G01X211417Y547244D02*
X212992Y545669D01*
G01X165777Y542555D02*
X165775D01*
Y542545D01*
X167323Y544093D01*
Y544094D01*
G01X204979Y525545D02*
Y521829D01*
X203500Y520350D01*
G01X205118Y537795D02*
Y536756D01*
X201960Y533598D01*
Y528564D01*
X204979Y525545D01*
G01X213050Y525000D02*
Y526600D01*
X213950Y527500D01*
Y533186D01*
X209882Y537254D01*
Y538090D01*
X208700Y539272D01*
X207773D01*
X206100Y540945D01*
X205118D01*
G01X208267Y556693D02*
X208268D01*
X209842Y555119D01*
G01X208267Y553543D02*
X208268D01*
X209842Y551969D01*
G01X206692Y548820D02*
X205118Y550394D01*
G01X206693Y551969D02*
X206692D01*
X205118Y553543D01*
G01X195669Y547244D02*
X194094Y545669D01*
G01X190929Y512592D02*
X191508D01*
X193850Y510250D01*
Y507900D01*
X195500Y506250D01*
G01X194094Y548820D02*
Y548994D01*
X195494Y550394D01*
X195669D01*
G01X176771D02*
X176770D01*
X175197Y548821D01*
G01X170472Y547244D02*
Y547243D01*
X168898Y545669D01*
G01X154724Y540945D02*
X153150Y539371D01*
G01X153149Y542521D02*
X153151D01*
X154724Y544094D01*
G01X195669D02*
X197244Y545669D01*
G01X198819Y540945D02*
X198818D01*
X197244Y542519D01*
G01X174400Y516150D02*
Y519283D01*
G01X157874Y540945D02*
X156300Y539371D01*
G01X205118Y594488D02*
Y594489D01*
X206692Y596063D01*
G01X208267Y603937D02*
Y606967D01*
X214573Y613273D01*
Y615684D01*
X212750Y617507D01*
Y618700D01*
G01X223593Y634091D02*
X220691D01*
X219300Y632700D01*
Y625800D01*
X215239Y621739D01*
Y617140D01*
X216100Y616279D01*
Y613300D01*
X209862Y607062D01*
Y602382D01*
X208267Y600787D01*
G01X203450Y592912D02*
X203600D01*
Y592856D01*
X205118Y591338D01*
G01X212991Y567718D02*
X212990D01*
X211417Y569291D01*
G01Y572441D02*
X211416D01*
X209841Y574016D01*
G01X208267Y572441D02*
X206692Y574016D01*
G01X170472Y569291D02*
X168898Y567717D01*
G01X159449Y570866D02*
X161023Y572440D01*
Y572441D01*
G01X170472Y581890D02*
X168898Y583464D01*
G01Y577165D02*
X170472Y575591D01*
Y575590D01*
G01X159449Y586614D02*
X161023Y585040D01*
Y585039D01*
G01X164173Y581890D02*
X162598Y580315D01*
G01X164173Y585039D02*
X162598Y586614D01*
G01X167323Y585039D02*
X165748Y586614D01*
G01X168898D02*
X170472Y585040D01*
Y585039D01*
G01X159449Y577165D02*
X161023Y575591D01*
Y575590D01*
G01X157874D02*
X156299Y577165D01*
G01X168898Y580315D02*
X170472Y578741D01*
Y578740D01*
G01X159449Y580315D02*
X161023Y578741D01*
Y578740D01*
G01X164173D02*
X162598Y577165D01*
G01X167323Y578740D02*
X165748Y580315D01*
G01X162598Y583464D02*
X161024Y581890D01*
X161023D01*
G01X167323Y572441D02*
X165748Y570866D01*
G01Y567717D02*
X164174Y569291D01*
X164173D01*
G01X162598Y567717D02*
X161024Y569291D01*
X161023D01*
G01X211417Y578740D02*
X212992Y580315D01*
G01X212991Y577165D02*
Y577164D01*
X211417Y575590D01*
G01X209842Y567717D02*
X209841D01*
X208267Y569291D01*
G01X190945Y599213D02*
X189370Y597638D01*
G01X190944Y596063D02*
X189370Y594489D01*
Y594488D01*
G01Y603937D02*
Y612729D01*
X191435Y614794D01*
G01X193285Y622650D02*
Y616644D01*
X191435Y614794D01*
G01X183071Y600787D02*
X184707Y602423D01*
Y609534D01*
X187140Y611967D01*
Y617507D01*
X187221D01*
G01X189185Y622650D02*
Y619471D01*
X187221Y617507D01*
G01X182819Y617616D02*
Y619189D01*
X185085Y621455D01*
Y622650D01*
G01X182819Y617616D02*
X182570Y617367D01*
Y604438D01*
X183071Y603937D01*
G01X176993Y613763D02*
Y613198D01*
X179921Y610270D01*
Y603937D01*
G01X180985Y622650D02*
X179390Y621055D01*
Y618190D01*
X176993Y615793D01*
Y613763D01*
G01X175300Y618164D02*
X174590Y617454D01*
Y612157D01*
X178300Y608447D01*
Y602408D01*
X179921Y600787D01*
G01X176800Y622650D02*
Y619664D01*
X175300Y618164D01*
G01D02*
Y618200D01*
G01X176771Y603937D02*
Y607449D01*
X172048Y612172D01*
Y614508D01*
G01D02*
Y616921D01*
X172450Y617323D01*
Y622400D01*
X172700Y622650D01*
G01X157458Y633782D02*
X161958D01*
G01X166500Y633750D02*
X166468Y633782D01*
X161958D01*
G01X166500Y633750D02*
Y629772D01*
X169600Y626672D01*
Y624941D01*
X170450Y624091D01*
Y619300D01*
X169998Y618848D01*
Y612130D01*
X175348Y606780D01*
Y603110D01*
X176771Y601687D01*
Y600787D01*
G01X187796Y599212D02*
X189370Y600786D01*
Y600787D01*
G01X183071Y597638D02*
X181586Y599123D01*
G01X212991Y583465D02*
X211417Y581891D01*
Y581890D01*
G01X209841Y577165D02*
Y577164D01*
X208267Y575590D01*
G01X157874Y594488D02*
X156174Y596188D01*
X154123D01*
X153274Y597037D01*
Y597606D01*
X146174Y604706D01*
Y610359D01*
X144558Y611975D01*
X143221D01*
G01X174700Y633750D02*
Y630402D01*
X174799Y630303D01*
G01X176800Y626150D02*
X174799Y628151D01*
Y630303D01*
G01X171400Y630200D02*
Y630900D01*
X170600Y631700D01*
Y633750D01*
G01X172700Y626150D02*
Y626303D01*
X171400Y627603D01*
Y630200D01*
G01X140800Y616400D02*
X142801Y614399D01*
X143928D01*
X147100Y611227D01*
Y605087D01*
X154549Y597638D01*
X154724D01*
G01X161023Y594488D02*
X159448Y596063D01*
G01X192519Y600787D02*
X190944Y602362D01*
G01X199950Y614000D02*
X192519Y606569D01*
Y603937D01*
G01X142572Y633682D02*
X147318D01*
X151900Y629100D01*
Y628050D01*
X153700Y626250D01*
G01X142572Y633682D02*
Y633047D01*
X144737Y630882D01*
G01X205118Y600787D02*
X203543Y602362D01*
G01X200100Y633300D02*
X201200Y634400D01*
X202500D01*
X204100Y636000D01*
Y637950D01*
G01X201968Y594488D02*
Y594489D01*
X203542Y596063D01*
G01X209193Y614249D02*
Y612493D01*
X205300Y608600D01*
Y604119D01*
X205118Y603937D01*
G01X194094Y599213D02*
X192519Y597638D01*
G01X168898Y596063D02*
Y596062D01*
X170472Y594488D01*
G01X211417Y597638D02*
X212991Y599212D01*
G01X211417Y597638D02*
X212904Y596151D01*
X215188D01*
X216366Y594973D01*
Y593928D01*
X217156Y593138D01*
X218276D01*
X219626Y594488D01*
X220866D01*
G01X211417Y603937D02*
Y600787D01*
G01X206692Y589763D02*
X206693D01*
X208267Y588189D01*
G01X211417Y600787D02*
X214567D01*
G01X168898Y592913D02*
Y592912D01*
X170472Y591338D01*
G01X164173Y594488D02*
X162598Y596063D01*
G01X194093Y589764D02*
Y589763D01*
X192519Y588189D01*
G01X194093Y592913D02*
X192519Y591339D01*
Y591338D01*
G01X149800Y618700D02*
X151200Y617300D01*
X152600D01*
X153500Y616400D01*
Y613511D01*
X162473Y604538D01*
Y603727D01*
X163613Y602587D01*
X165523D01*
X167323Y600787D01*
G01X149400Y623150D02*
Y619100D01*
X149800Y618700D01*
G01X164173Y600787D02*
X163350D01*
X161900Y602237D01*
X154232D01*
X149400Y607069D01*
Y613164D01*
X147262Y615302D01*
G01X145279Y619120D02*
Y617285D01*
X147262Y615302D01*
G01X182876Y633018D02*
Y630576D01*
X182100Y629800D01*
G01X185085Y626150D02*
X182100Y629135D01*
Y629800D01*
G01X180985Y626150D02*
X178200Y628935D01*
Y629800D01*
G01X178776Y633018D02*
Y630376D01*
X178200Y629800D01*
G01X208267Y585039D02*
X206692Y586614D01*
G01X209842Y586613D02*
X209843D01*
X211417Y585039D01*
G01X212992Y589764D02*
X211418Y591338D01*
X211417D01*
G01Y594488D02*
X211416D01*
X209841Y592913D01*
G01X164173Y572441D02*
X162598Y570866D01*
G01X148210Y629830D02*
Y627840D01*
X149400Y626650D01*
G01X144993Y626564D02*
X145279Y626278D01*
Y622620D01*
G01X144993Y626564D02*
X143640D01*
X141742Y624666D01*
G01X142500Y599062D02*
X149272D01*
X151451Y596883D01*
Y595851D01*
X154164Y593138D01*
X156074D01*
X157874Y591338D01*
G01X165800Y623700D02*
X164200Y622100D01*
Y617839D01*
X166719Y615320D01*
Y611566D01*
X172000Y606285D01*
Y602409D01*
X173622Y600787D01*
G01X167400Y618300D02*
X168350Y617350D01*
Y611784D01*
X173622Y606512D01*
Y603937D01*
G01X161900Y627800D02*
X162700Y627000D01*
Y617217D01*
X165300Y614617D01*
Y611712D01*
X170472Y606540D01*
Y603937D01*
G01X160100Y622300D02*
X161100Y621300D01*
Y610000D01*
X164400Y606700D01*
X166470D01*
X168712Y604458D01*
Y602547D01*
X170472Y600787D01*
G01X179921Y594488D02*
Y594489D01*
X178346Y596064D01*
G01X179921Y597638D02*
Y597639D01*
X178347Y599213D01*
G01X167323Y597638D02*
X165748Y599213D01*
G01X168898D02*
Y599212D01*
X170472Y597638D01*
G01X164173D02*
X162598Y599213D01*
G01X161023Y597638D02*
X159448Y599213D01*
G01X172048Y596063D02*
Y596062D01*
X173622Y594488D01*
G01X153700Y622750D02*
Y619792D01*
X155378Y618114D01*
G01D02*
X156000Y617492D01*
Y614863D01*
X156992Y613871D01*
Y611292D01*
X164173Y604111D01*
Y603937D01*
G01X211417Y588189D02*
X211416D01*
X209842Y589763D01*
G01X205118Y578740D02*
Y578741D01*
X206692Y580315D01*
G01X209841D02*
Y580314D01*
X208267Y578740D01*
G01X211417Y566142D02*
X212992Y564567D01*
G01X183071Y594488D02*
X182912D01*
X181500Y595900D01*
G01X201968Y600787D02*
X201813D01*
X200400Y602200D01*
Y606585D01*
X207400Y613585D01*
Y617885D01*
X206636Y618649D01*
G01X200393Y592912D02*
X200394D01*
X201968Y591338D01*
G01X208267Y597638D02*
X209841Y599212D01*
G01X201968Y597638D02*
X201967D01*
X200393Y599212D01*
G01X205118Y597638D02*
X206716Y599236D01*
Y606816D01*
X211200Y611300D01*
Y615000D01*
X210100Y616100D01*
Y621180D01*
X210800Y621880D01*
Y622500D01*
G01D02*
X211420D01*
X214450Y625530D01*
Y625850D01*
X215400Y626800D01*
G01X161023Y588189D02*
X159448Y589764D01*
G01X161023Y591338D02*
X159448Y592913D01*
G01X164173Y588189D02*
X162598Y589764D01*
G01X167323Y588189D02*
X165748Y589764D01*
G01X167323Y594488D02*
X165748Y596063D01*
G01X167323Y591338D02*
X165748Y592913D01*
G01X191076Y633148D02*
Y631774D01*
X188899Y629597D01*
G01X193285Y626150D02*
X192346D01*
X188899Y629597D01*
G01X189185Y626150D02*
X189050D01*
X185500Y629700D01*
G01X186976Y633018D02*
Y631176D01*
X185500Y629700D01*
G01X157450Y626650D02*
Y620278D01*
X158500Y619228D01*
Y611200D01*
X164000Y605700D01*
X165560D01*
X167323Y603937D01*
G01X154500Y629600D02*
X157450Y626650D01*
G01X150872Y633682D02*
X154500Y630054D01*
Y629600D01*
G01X176771Y591338D02*
Y591339D01*
X175197Y592913D01*
G01X173622Y591338D02*
Y591339D01*
X172048Y592913D01*
G01X183071Y591338D02*
X182957D01*
X181530Y592765D01*
G01X176771Y594488D02*
Y594489D01*
X175197Y596063D01*
G01X176771Y597638D02*
Y597639D01*
X175197Y599213D01*
G01X173622Y597638D02*
Y597639D01*
X172048Y599213D01*
G01X204100Y637950D02*
X207900D01*
G01D02*
X211698D01*
X211706Y637942D01*
G01X209764Y688956D02*
Y693964D01*
X213350Y697550D01*
X236850D01*
X239600Y700300D01*
Y709500D01*
X242450Y712350D01*
X249897D01*
X253504Y715957D01*
X261305D01*
G01X214723Y655546D02*
X210123D01*
G01D02*
X208146D01*
X207000Y654400D01*
G01X267950Y458200D02*
X265000D01*
X262900Y460300D01*
X259079D01*
G01X268350Y489500D02*
X264834D01*
X264034Y490300D01*
X259079D01*
G01X269100Y509063D02*
X272500Y505663D01*
Y493650D01*
X268350Y489500D01*
G01X271450Y474380D02*
X272980D01*
X275113Y476513D01*
G01X221225Y460300D02*
X220521D01*
G01D02*
X213185D01*
X213159Y460326D01*
G01X266664Y493000D02*
X264364Y495300D01*
X259079D01*
G01X221225Y465300D02*
X220521D01*
G01X214808Y463300D02*
X216808Y465300D01*
X220521D01*
G01X225262Y515130D02*
Y512362D01*
X224500Y511600D01*
Y503300D01*
X230500Y497300D01*
Y490700D01*
X231400Y489800D01*
G01X237903D02*
X234550Y493153D01*
Y504967D01*
X235626Y506043D01*
Y511726D01*
X237344Y513444D01*
G01X338963Y440163D02*
X334826Y444300D01*
X302582D01*
X283400Y463482D01*
Y471262D01*
X276600Y478062D01*
Y483700D01*
X276591Y483709D01*
G01X314666Y246260D02*
X330946D01*
X332492Y244714D01*
X336393D01*
X345357Y253678D01*
X354292D01*
X360759Y260145D01*
Y364388D01*
X370829Y374458D01*
Y430094D01*
X366301Y434622D01*
X339232D01*
X333054Y440800D01*
X301829D01*
X288829Y453800D01*
X259314D01*
X246500Y466614D01*
Y476500D01*
X244400Y478600D01*
G01X357846Y260273D02*
X358400Y260827D01*
Y364858D01*
X368829Y375287D01*
Y429265D01*
X365472Y432622D01*
X338403D01*
X332225Y438800D01*
X301000D01*
X288000Y451800D01*
X258485D01*
X244300Y465985D01*
Y474150D01*
G01X267950Y474380D02*
Y470300D01*
G01D02*
X259079D01*
G01X274245Y546834D02*
X276534D01*
X276995Y547295D01*
Y558100D01*
G01X275875Y541121D02*
Y543234D01*
X274245Y544864D01*
Y546834D01*
G01X276995Y558100D02*
X280589Y561694D01*
X280995D01*
G01X216141Y564569D02*
X214568Y566142D01*
X214567D01*
G01X237980Y555707D02*
X232559D01*
X223916Y564350D01*
X219508D01*
X217716Y566142D01*
G01X239546Y564498D02*
X238402D01*
X236051Y566849D01*
X233641D01*
X232873Y566081D01*
X230838D01*
G01X235484Y561538D02*
X234943Y562079D01*
Y565199D01*
G01X239546Y560398D02*
X236624D01*
X235484Y561538D01*
G01X216141Y561419D02*
X216140D01*
X214567Y562992D01*
G01X227600Y563000D02*
X224458Y566142D01*
X220866D01*
G01X288100Y542900D02*
X287427D01*
X283493Y546834D01*
X281645D01*
G01Y551954D02*
X282829D01*
X286591Y555716D01*
X288416D01*
X288883Y555249D01*
G01X267514Y544035D02*
Y547786D01*
X266700Y548600D01*
G01D02*
Y552350D01*
X267450Y553100D01*
G01D02*
X269700D01*
X270846Y551954D01*
X274245D01*
G01X267514Y540535D02*
X263765D01*
X263600Y540700D01*
G01X226357Y504514D02*
X229342Y507499D01*
Y514905D01*
G01X258375Y495300D02*
X259079D01*
G01X246688Y528501D02*
X249293Y531106D01*
X250901D01*
G01D02*
X256042D01*
X257894Y529254D01*
G01X258969Y537520D02*
Y541471D01*
G01Y537520D02*
X261430D01*
X263600Y535350D01*
G01X221014Y526000D02*
Y533770D01*
X218266Y536518D01*
Y536559D01*
X217716Y537109D01*
Y537795D01*
G01X225262Y518630D02*
Y521752D01*
X221014Y526000D01*
G01X237344Y513444D02*
X239050Y515150D01*
Y520563D01*
G01X217716Y540945D02*
X218764D01*
X220464Y539245D01*
X221750D01*
X225450Y535545D01*
Y529346D01*
X227596Y527200D01*
X228500D01*
X232301Y523399D01*
Y517599D01*
X233900Y516000D01*
G01D02*
X234900D01*
X235550Y516650D01*
Y520563D01*
G01X248027Y563068D02*
X250045Y561050D01*
X260450D01*
X261385Y561985D01*
X261404D01*
X262663Y563244D01*
Y563263D01*
X265366Y565966D01*
X271966D01*
G01X243046Y564498D02*
X244476Y563068D01*
X248027D01*
G01X243046Y560398D02*
X246222Y557222D01*
X246522D01*
X246683Y557061D01*
X247946D01*
G01X266325Y557905D02*
X268330D01*
X274525Y564100D01*
X290285D01*
X293428Y567243D01*
X299124D01*
G01X247946Y557061D02*
X249859Y558974D01*
X257897D01*
X258948Y557923D01*
X266307D01*
X266325Y557905D01*
G01X219291Y542519D02*
X217716Y544094D01*
G01X214567D02*
Y544093D01*
X216141Y542519D01*
G01X220866Y540945D02*
X222198D01*
X227000Y536143D01*
Y531082D01*
X228541Y529541D01*
G01D02*
X233382Y524700D01*
X235659D01*
G01X239159D02*
X242900D01*
X243950Y523650D01*
Y522900D01*
G01D02*
Y515807D01*
X240500Y512357D01*
Y508300D01*
X236400Y504200D01*
Y502150D01*
G01X231800Y538900D02*
X230431Y540269D01*
X228015D01*
X221040Y547244D01*
X220866D01*
G01X241313Y539142D02*
X242896D01*
X245378Y536660D01*
G01X241313Y539142D02*
X238823Y536652D01*
X234048D01*
X231800Y538900D01*
G01X245378Y536660D02*
Y533951D01*
X246508Y532821D01*
G01X216142Y548820D02*
X214568Y550394D01*
X214567D01*
G01X217716Y556693D02*
X219409Y555000D01*
X223141D01*
X227320Y550821D01*
Y549191D01*
X231511Y545000D01*
Y544474D01*
X233882Y542103D01*
X236463D01*
X236866Y541700D01*
X243783D01*
X244083Y542000D01*
X245300D01*
X247300Y544000D01*
G01X216141Y555120D02*
X216140D01*
X214567Y556693D01*
G01X235700Y544500D02*
X234600D01*
X229963Y549137D01*
Y552853D01*
X227316Y555500D01*
X226300D01*
X223353Y558447D01*
X219111D01*
X217716Y559842D01*
G01X216141Y558269D02*
X216140D01*
X214567Y559842D01*
G01X220866Y562992D02*
X223808D01*
X232749Y554051D01*
X234849D01*
X238100Y550800D01*
G01X241100Y544100D02*
X238550Y546650D01*
X234850D01*
X230864Y550636D01*
Y553225D01*
X224247Y559842D01*
X220866D01*
G01X222441Y548820D02*
X220867Y550394D01*
X220866D01*
G01X219291Y548820D02*
X217717Y550394D01*
X217716D01*
G01X214567Y553543D02*
X214568D01*
X216141Y551970D01*
G01X228100Y545500D02*
X225790Y547810D01*
Y550890D01*
X223137Y553543D01*
X220866D01*
G01X228800Y542100D02*
X224276Y546624D01*
Y551131D01*
X223307Y552100D01*
X219159D01*
X217716Y553543D01*
G01X220866Y556693D02*
X223307D01*
X227831Y552169D01*
X228313D01*
G01X243700Y555550D02*
X241250Y558000D01*
X233936D01*
X233607Y557671D01*
G01X229342Y518405D02*
X229762Y518825D01*
Y522829D01*
G01X212150Y495300D02*
X220521D01*
G01X238168Y529269D02*
X233444D01*
X228100Y534613D01*
Y536860D01*
X220866Y544094D01*
G01X235658Y534262D02*
X232749D01*
X221355Y545656D01*
X219304D01*
X217716Y547244D01*
G01X219250Y512066D02*
Y516550D01*
X219800Y517100D01*
G01D02*
X220862Y518162D01*
Y521308D01*
X218964Y523206D01*
Y533023D01*
X214567Y537420D01*
Y537795D01*
G01X212600Y520450D02*
X213050Y520900D01*
Y525000D01*
G01X216142Y545669D02*
X214567Y547244D01*
G01X242449Y532550D02*
Y531048D01*
X243188Y530309D01*
Y528501D01*
G01X242449Y532550D02*
Y534722D01*
X241154Y536017D01*
G01X250445Y548551D02*
X254560D01*
G01D02*
X257327D01*
X258969Y546909D01*
Y544971D01*
G01X255800Y539600D02*
Y541700D01*
X253202Y544298D01*
G01D02*
X251346Y546154D01*
X242346D01*
X240350Y548150D01*
X235472D01*
X233505Y550117D01*
X233183D01*
X232081Y551219D01*
Y553281D01*
X224620Y560742D01*
X224580D01*
X224122Y561200D01*
X219508D01*
X217716Y562992D01*
G01X283550Y535000D02*
X282600D01*
X279200Y531600D01*
G01X351250Y500200D02*
X347050Y504400D01*
X336000D01*
X334793Y505607D01*
Y508707D01*
X330850Y512650D01*
X322950D01*
X318700Y516900D01*
X299400D01*
X297200Y514700D01*
X282400D01*
X277000Y520100D01*
Y529400D01*
X279200Y531600D01*
G01X212750Y618700D02*
Y621387D01*
X217800Y626437D01*
Y633983D01*
X215373Y636410D01*
Y637909D01*
X215406Y637942D01*
G01X228200Y639150D02*
X223593Y634543D01*
Y634091D01*
G01X216141Y580315D02*
X214567Y578741D01*
Y578740D01*
G01X232896Y613795D02*
X228553Y609452D01*
Y603274D01*
X221345Y596066D01*
X219294D01*
X217716Y594488D01*
G01X260705Y598359D02*
Y597605D01*
X258700Y595600D01*
X255535D01*
X253510Y593575D01*
G01X216141Y577165D02*
Y577164D01*
X214567Y575590D01*
G01X216141Y583465D02*
X214567Y581891D01*
Y581890D01*
G01X271150Y605800D02*
Y611390D01*
X270521Y612019D01*
G01X267650Y605800D02*
Y597050D01*
X267600Y597000D01*
G01X214567Y569291D02*
X214568D01*
X216141Y567718D01*
G01X220866Y569291D02*
Y569290D01*
X219293Y567717D01*
G01X217716Y569291D02*
X219066Y570641D01*
X221426D01*
X223789Y568278D01*
X226139D01*
X228336Y566081D01*
X230838D01*
G01X214567Y572441D02*
X214566D01*
X212991Y574016D01*
G01X217716Y572441D02*
X216141Y574016D01*
G01X220866Y572441D02*
X222512D01*
X224703Y570250D01*
X229043D01*
X230393Y568900D01*
X234797D01*
G01X238575Y568522D02*
X238197Y568900D01*
X234797D01*
G01X241092Y572585D02*
X238889Y574788D01*
X236421D01*
G01D02*
X234949D01*
X234411Y574250D01*
X224223D01*
X222883Y575590D01*
X220866D01*
G01X240150Y585700D02*
X235310D01*
G01D02*
X234400D01*
X232708Y584008D01*
Y580908D01*
X230540Y578740D01*
X220866D01*
G01X217716D02*
X219066Y577390D01*
X223915D01*
X226155Y575150D01*
X232218D01*
X234034Y576966D01*
Y578517D01*
G01X238808Y581690D02*
X237182D01*
X234031Y578539D01*
Y578517D01*
X234034D01*
G01X286703Y618461D02*
X283203D01*
X283149Y618515D01*
X279745D01*
G01X214567Y603937D02*
X214566D01*
X212992Y602363D01*
G01X214567Y597638D02*
X216141Y599212D01*
G01D02*
X214567Y600786D01*
Y600787D01*
G01X271966Y565966D02*
X272178D01*
X272312Y566100D01*
X289456D01*
X293159Y569803D01*
X299124D01*
G01X262694Y568076D02*
X261695D01*
X258771Y571000D01*
X257000D01*
X255500Y569500D01*
X252915D01*
X250675Y567260D01*
G01X246433Y567987D02*
X247160Y567260D01*
X250675D01*
G01X246433Y567987D02*
X245898Y568522D01*
X242075D01*
G01X260131Y574893D02*
X260735D01*
X261300Y574328D01*
Y571300D01*
G01X260131Y574893D02*
X258438Y573200D01*
X256371D01*
X254810Y571639D01*
X250411D01*
X248550Y573500D01*
G01D02*
X247635Y572585D01*
X244592D01*
G01X221900Y623650D02*
X220550D01*
X217600Y620700D01*
G01X225900Y623650D02*
X221900D01*
G01X217600Y620700D02*
Y612984D01*
X216200Y611584D01*
Y605453D01*
X217716Y603937D01*
G01X229952Y626380D02*
X231500Y624832D01*
Y624284D01*
X234000Y621784D01*
Y621750D01*
G01X226300Y618800D02*
X229464Y621964D01*
Y625892D01*
X229952Y626380D01*
G01X226300Y618800D02*
X224200Y616700D01*
Y604121D01*
X220866Y600787D01*
G01X238000Y621750D02*
X236200Y619950D01*
X233382D01*
X231913Y618481D01*
Y617900D01*
X225464Y611451D01*
Y603334D01*
X221467Y599337D01*
X219415D01*
X217716Y597638D01*
G01X237800Y629800D02*
X239850Y627750D01*
Y623600D01*
X238000Y621750D01*
G01X236150Y634300D02*
Y631450D01*
X237800Y629800D01*
G01X240250Y589800D02*
X238550Y588100D01*
X234401D01*
X226841Y580540D01*
X219066D01*
X217716Y581890D01*
G01X240250Y589800D02*
X242350Y591900D01*
X249487D01*
X250087Y591300D01*
G01D02*
X251808Y589579D01*
X255008D01*
G01X236056Y596885D02*
X225571Y586400D01*
X219077D01*
X217716Y585039D01*
G01X236056Y596885D02*
X237195Y598024D01*
Y598345D01*
X239850Y601000D01*
G01X217716Y591338D02*
X218956D01*
X220306Y592688D01*
X220976D01*
X229900Y601612D01*
Y604264D01*
X235614Y609978D01*
G01X221898Y618622D02*
X220100Y616824D01*
Y608000D01*
X219295Y607195D01*
Y602366D01*
X217716Y600787D01*
G01X258596Y586356D02*
X257295Y585055D01*
X257206D01*
X255935Y583784D01*
G01X243650Y585700D02*
X247650D01*
G01D02*
X248103D01*
X250433Y583370D01*
X255521D01*
X255935Y583784D01*
G01X248650Y578300D02*
X251720Y581370D01*
X258024D01*
X259848Y583194D01*
G01X248650Y578300D02*
X247472Y577122D01*
X242866D01*
G01D02*
X242308Y577680D01*
Y581690D01*
G01X272169Y574462D02*
X272659D01*
X275652Y577455D01*
G01X261455Y579009D02*
Y580761D01*
X262694Y582000D01*
X267600D01*
G01X268669Y574462D02*
X267301D01*
X264914Y576849D01*
X262580D01*
X261455Y577974D01*
Y579009D01*
G01X214567Y591338D02*
Y591336D01*
X216141Y589762D01*
G01X214567Y594488D02*
Y594486D01*
X212993Y592912D01*
G01X220866Y597638D02*
X221665Y598437D01*
X221840D01*
X226364Y602961D01*
Y609969D01*
X232026Y615631D01*
X232473D01*
X234087Y617245D01*
Y618038D01*
G01X259000Y617000D02*
Y616497D01*
X255853Y613350D01*
X251900D01*
G01X247900Y616850D02*
X243900D01*
G01X251900Y613350D02*
X248400Y616850D01*
X247900D01*
G01X220866Y591338D02*
X220899D01*
X231683Y602122D01*
Y604317D01*
X233566Y606200D01*
X234877D01*
X238900Y610223D01*
Y611998D01*
X239963Y613061D01*
G01D02*
X240252Y613350D01*
X243900D01*
G01X217716Y575590D02*
X219515Y573791D01*
X223409D01*
X225500Y571700D01*
X228866D01*
X230316Y570250D01*
X232416D01*
X234166Y572000D01*
X234800D01*
G01X258823Y628096D02*
Y631323D01*
X258873Y631373D01*
G01X262823Y628146D02*
X258873D01*
X258823Y628096D01*
G01X260500Y637500D02*
X258873Y635873D01*
Y631373D01*
G01X265750Y639500D02*
X262500D01*
X260500Y637500D01*
G01X261025Y593260D02*
X262440D01*
X263700Y592000D01*
X267600D01*
G01X261025Y593260D02*
X257325D01*
X257010Y593575D01*
G01X223400Y637950D02*
X221800D01*
X221000Y638750D01*
X219200D01*
G01D02*
X217401D01*
X216626Y637975D01*
X215439D01*
X215406Y637942D01*
G01X236000Y639150D02*
X232000D01*
G01D02*
X228200D01*
G01X254900Y701950D02*
X254620Y702230D01*
X251600D01*
X251580Y702250D01*
X247500D01*
G01D02*
X248531Y701219D01*
Y692774D01*
G01X277600Y674600D02*
Y680200D01*
G01X217638Y688956D02*
Y695562D01*
G01X239000Y687300D02*
X237200Y685500D01*
Y678712D01*
X235659Y677171D01*
Y668096D01*
X230056Y662493D01*
X227884D01*
X227834Y662443D01*
X226034D01*
X225984Y662493D01*
G01D02*
X223544Y664933D01*
Y670886D01*
G01X239000Y691000D02*
Y687300D01*
G01X274650Y640772D02*
Y644572D01*
G01D02*
Y652427D01*
X275956Y653733D01*
G01X281602Y657563D02*
X283300Y659261D01*
Y676200D01*
X279800Y679700D01*
Y681100D01*
X278400Y682500D01*
X275700D01*
X273800Y684400D01*
Y686350D01*
G01X281602Y657563D02*
X279427Y655388D01*
X277611D01*
X275956Y653733D01*
G01X259550Y666000D02*
Y663150D01*
X258400Y662000D01*
G01X259526Y669731D02*
Y666024D01*
X259550Y666000D01*
G01X259526Y669731D02*
Y671900D01*
X260326Y672700D01*
X265400D01*
X266200Y671900D01*
X267100D01*
G01X252250Y662625D02*
X254875D01*
X255500Y662000D01*
X258400D01*
G01X276360Y692850D02*
Y697210D01*
X276400Y697250D01*
G01X247500Y705750D02*
X252400D01*
G01D02*
X252750D01*
X254700Y707700D01*
Y708900D01*
G01X271220Y679910D02*
Y682940D01*
X271240Y682960D01*
Y686350D01*
G01X271200Y676150D02*
Y679890D01*
X271220Y679910D01*
G01X258500Y679250D02*
X255650D01*
X255000Y679900D01*
G01X258371Y686074D02*
Y681587D01*
X258500Y681458D01*
Y679250D01*
G01X244750Y652500D02*
X253014D01*
X255800Y649714D01*
X258000D01*
G01Y653750D02*
Y649714D01*
G01Y653750D02*
X262335D01*
G01D02*
X264598D01*
X268456Y657608D01*
G01X261305Y715957D02*
X264500D01*
X265095Y715362D01*
Y701705D01*
X267100Y699700D01*
G01X238807Y658621D02*
X237490D01*
X235042Y656173D01*
G01X246700Y675850D02*
Y674270D01*
X244750Y672320D01*
Y666500D01*
G01X263491Y692574D02*
Y697136D01*
X266055Y699700D01*
X267100D01*
G01X243100Y677500D02*
X244750Y675850D01*
X246700D01*
G01X238939Y662667D02*
Y664467D01*
X240972Y666500D01*
X244750D01*
G01X238939Y662667D02*
Y660867D01*
X238807Y660735D01*
Y658621D01*
G01X260332Y642199D02*
X262487D01*
X263500Y643212D01*
G01X250800Y679350D02*
X246700D01*
G01D02*
X242092D01*
X239842Y681600D01*
G01D02*
Y683642D01*
X242474Y686274D01*
X245971D01*
G01X252250Y648625D02*
Y643850D01*
X252700Y643400D01*
G01X256832Y642199D02*
X253901D01*
X252700Y643400D01*
G01X218623Y655596D02*
X214773D01*
X214723Y655546D01*
G01X266400Y662200D02*
X264023Y659823D01*
X245823D01*
X241121Y655121D01*
X238807D01*
G01X270100Y662700D02*
X269600Y662200D01*
X266400D01*
G01D02*
Y664800D01*
X267100Y665500D01*
Y668300D01*
G01X277600Y665600D02*
X276500D01*
X273600Y662700D01*
X270100D01*
G01X353543Y55039D02*
X355904Y57400D01*
X362100D01*
X371300Y48200D01*
X372520D01*
G01X353543Y62913D02*
X355956Y60500D01*
X364000D01*
X371700Y52800D01*
X372520D01*
G01X352000Y109000D02*
X354000Y111000D01*
Y112260D01*
G01X355500Y109000D02*
X361500D01*
X363000Y110500D01*
Y112260D01*
G01X372220Y86300D02*
X368700D01*
X366600Y84200D01*
X355878D01*
X353543Y86535D01*
G01X372220Y81700D02*
X356582D01*
X353543Y78661D01*
G01X294720Y182200D02*
X300200D01*
X304600Y177800D01*
X320700D01*
G01X314666Y192717D02*
Y190694D01*
X316482Y188878D01*
X326942D01*
X333643Y182177D01*
X335921D01*
X335922Y182178D01*
X336770D01*
X338955Y179994D01*
G01X343582Y178428D02*
X347782D01*
X348032Y178678D01*
G01X343582Y178428D02*
X340521D01*
X338955Y179994D01*
G01X350408Y393708D02*
X350400Y393700D01*
X347500D01*
X339400Y385600D01*
Y279496D01*
X333882Y273978D01*
G01X348006Y391300D02*
X348000Y391294D01*
Y388300D01*
X340900Y381200D01*
Y277596D01*
X333882Y270578D01*
G01X343768Y232181D02*
Y236246D01*
X347715Y240193D01*
X356187D01*
X370759Y254765D01*
Y347672D01*
X383150Y360063D01*
Y426260D01*
X368788Y440622D01*
X356505D01*
X353627Y443500D01*
X350300D01*
G01X343768Y232181D02*
Y228047D01*
X343798Y228017D01*
G01X340268Y232181D02*
X338468D01*
X337571Y233078D01*
X335098D01*
G01X297146Y233661D02*
X302995D01*
X305782Y230874D01*
G01X346300Y374600D02*
Y276867D01*
X340100Y270667D01*
Y269396D01*
X334482Y263778D01*
G01X333782Y267178D02*
X342900Y276296D01*
Y376300D01*
X345700Y379100D01*
X349100D01*
G01X370730Y241308D02*
X366302Y236880D01*
X348002D01*
X346700Y235578D01*
Y227578D01*
X344200Y225078D01*
X326278D01*
X324000Y222800D01*
G01X351411Y251004D02*
X354998D01*
X358050Y254056D01*
G01X314666Y243110D02*
X331051D01*
X331447Y242714D01*
X337449D01*
X342228Y247493D01*
G01X347911Y251004D02*
X345739D01*
X342228Y247493D01*
G01X314666Y236811D02*
X328626D01*
X329330Y237515D01*
X338337D01*
X345650Y244828D01*
X355150D01*
X366759Y256437D01*
Y349330D01*
X379150Y361721D01*
Y424602D01*
X367130Y436622D01*
X342504D01*
X338963Y440163D01*
G01X351412Y242193D02*
X355358D01*
X368759Y255594D01*
Y348501D01*
X381150Y360892D01*
Y425431D01*
X367959Y438622D01*
X355676D01*
X354198Y440100D01*
X347800D01*
G01X314666Y233661D02*
X328305D01*
X330159Y235515D01*
X339506D01*
X341105Y237114D01*
G01X347912Y242193D02*
X346184D01*
X341105Y237114D01*
G01X351532Y257778D02*
X356400Y262646D01*
Y369354D01*
X359323Y372277D01*
G01X334198Y248824D02*
X334845D01*
X343799Y257778D01*
X348032D01*
G01X297146Y246260D02*
X303426D01*
X305225Y244461D01*
X305454D01*
G01X363699Y382608D02*
X358266D01*
X350400Y374742D01*
Y268246D01*
X347932Y265778D01*
G01X340000Y262678D02*
X335596Y258274D01*
X321082D01*
X320498Y258858D01*
X314666D01*
G01X344432Y265778D02*
X343100D01*
X340000Y262678D01*
G01X363703Y386008D02*
X358837D01*
X348400Y375571D01*
Y275046D01*
X347882Y274528D01*
G01X343582Y271028D02*
X342100Y269546D01*
Y268567D01*
X335310Y261777D01*
X322779D01*
X322548Y262008D01*
X314666D01*
G01X343582Y271028D02*
X347882D01*
G01X334282Y252378D02*
X335570D01*
X343228Y260036D01*
X348271D01*
X354400Y266165D01*
Y370975D01*
X359234Y375809D01*
X363586D01*
G01X297146Y252559D02*
X303915D01*
X305373Y251101D01*
G01X297146Y255709D02*
X305042D01*
X306412Y254339D01*
G01X334260Y255820D02*
X336183D01*
X342399Y262036D01*
X347442D01*
X352400Y266994D01*
Y372375D01*
X359233Y379208D01*
X363701D01*
G01X362349Y255239D02*
X362346D01*
X354111Y247004D01*
X351411D01*
G01X314666Y239961D02*
X323893D01*
X324289Y239565D01*
X337343D01*
X339387Y241609D01*
G01X347911Y247004D02*
X344782D01*
X339387Y241609D01*
G01X297146Y236811D02*
X303345D01*
X305882Y234274D01*
G01X297146Y239961D02*
X303584D01*
X305772Y237773D01*
Y237673D01*
G01X357846Y260273D02*
X353251Y255678D01*
X344528D01*
X335564Y246714D01*
X333323D01*
X331777Y248260D01*
X324254D01*
X323104Y249410D01*
X314666D01*
G01X297146Y243110D02*
X303747D01*
X305781Y241076D01*
G01X351285Y233565D02*
X354727D01*
X362431Y225861D01*
G01X297146Y378543D02*
X303151D01*
X303900Y379292D01*
Y380574D01*
G01X350900Y485348D02*
Y487417D01*
X351502Y488019D01*
Y495002D01*
X354300Y497800D01*
Y500245D01*
G01X350900Y485348D02*
Y470528D01*
X355778Y465650D01*
X359578D01*
X368550Y456678D01*
Y452050D01*
X369978Y450622D01*
X372933D01*
X373955Y449600D01*
X373956D01*
X374030Y449526D01*
G01X372575Y452600D02*
X371700Y453475D01*
Y457064D01*
X360614Y468150D01*
X356814D01*
X353700Y471264D01*
Y480668D01*
G01X362666Y504265D02*
X359015D01*
X357805Y503055D01*
Y497769D01*
X357500Y497464D01*
Y497400D01*
X354002Y493902D01*
Y486604D01*
X353700Y486302D01*
Y480668D01*
G01X350300Y443500D02*
X345600D01*
X344900Y442800D01*
G01X378937Y443491D02*
X378928Y443500D01*
X373690D01*
X371068Y446122D01*
X359432D01*
X342688Y462866D01*
Y495774D01*
X344755Y497841D01*
G01X376697Y446050D02*
X373969D01*
X371897Y448122D01*
X360261D01*
X344688Y463695D01*
Y493896D01*
G01X286061Y502378D02*
Y466502D01*
X304363Y448200D01*
X336367D01*
X344467Y440100D01*
X347800D01*
G01X695544Y21750D02*
X692214D01*
X684264Y13800D01*
X537463D01*
X535055Y11392D01*
X431208D01*
X425162Y17438D01*
Y51216D01*
X411039Y65339D01*
Y67238D01*
X378999Y99278D01*
Y244779D01*
X375000Y248778D01*
Y325122D01*
X375600Y325722D01*
Y349299D01*
X385150Y358849D01*
Y427089D01*
X369617Y442622D01*
X357334D01*
X349756Y450200D01*
X307501D01*
X291000Y466701D01*
Y502200D01*
X290000Y503200D01*
G01X382800Y353300D02*
X386650Y357150D01*
Y427711D01*
X370239Y444122D01*
X357956D01*
X350378Y451700D01*
X308123D01*
X295176Y464647D01*
Y501924D01*
X293800Y503300D01*
G01X292805Y546706D02*
X296254D01*
G01X284495Y561694D02*
X287306D01*
X288000Y561000D01*
G01X289305Y546706D02*
Y544079D01*
X288100Y542874D01*
Y542900D01*
G01X289550Y551300D02*
Y554582D01*
X288883Y555249D01*
G01X355600Y506600D02*
X358099Y509099D01*
X361439D01*
G01X355600Y513500D02*
X356200D01*
X356661Y513039D01*
X361439D01*
G01X307419Y527239D02*
X314911D01*
X316050Y526100D01*
G01X323750Y526000D02*
Y527950D01*
X327300Y531500D01*
Y540100D01*
G01X323750Y526000D02*
X321700Y528050D01*
X318000D01*
X316050Y526100D01*
G01X359088Y537881D02*
X355167D01*
X354677Y538371D01*
X350329D01*
X349600Y539100D01*
G01X345050Y543800D02*
Y539700D01*
X345100Y539650D01*
G01X349600Y539100D02*
X349050Y539650D01*
X345100D01*
G01X341226Y528459D02*
X342982D01*
X345864Y531341D01*
G01X350400Y531950D02*
X351331Y532881D01*
X359088D01*
G01X345864Y531341D02*
X346473Y531950D01*
X350400D01*
G01X359088Y527881D02*
X355256D01*
X351500Y524125D01*
G01X346819D02*
X342511D01*
X342497Y524111D01*
G01X351500Y524125D02*
X346819D01*
G01X338254Y559544D02*
X340894D01*
X341400Y560050D01*
G01X313791Y550221D02*
Y557409D01*
X312507Y558693D01*
X303958D01*
X303088Y559563D01*
X299124D01*
G01X313791Y550221D02*
X310270Y546700D01*
X307800D01*
G01X334754Y559544D02*
X330100D01*
G01D02*
X328131D01*
X325590Y557003D01*
X321324D01*
G01X338314Y555473D02*
X338856Y556015D01*
X341615D01*
G01X299124Y557003D02*
X302819D01*
X303129Y556693D01*
X307707D01*
X309596Y554804D01*
Y550103D01*
X309592Y550099D01*
G01D02*
X309136Y549643D01*
X305913D01*
G01X334814Y555473D02*
X328327D01*
X327900Y555900D01*
G01D02*
X326443Y554443D01*
X321324D01*
G01X348220Y563836D02*
X346577Y565479D01*
Y567339D01*
G01X342300Y571800D02*
X343682Y570418D01*
Y564974D01*
X344812Y563844D01*
G01X328200Y571800D02*
X327100Y570700D01*
Y567000D01*
X324783Y564683D01*
X321324D01*
G01X299124D02*
X303834D01*
X304436Y564081D01*
G01X330200Y568100D02*
X329200Y567100D01*
Y566271D01*
X325052Y562123D01*
X321324D01*
G01X338245Y563788D02*
X341311D01*
X341349Y563750D01*
G01X307350Y561290D02*
X304190D01*
X303357Y562123D01*
X299124D01*
G01X334745Y563788D02*
X330300D01*
X330188Y563900D01*
G01D02*
X329658D01*
X325321Y559563D01*
X321324D01*
G01X331000Y522100D02*
Y521100D01*
X334827Y517273D01*
Y517103D01*
G01X322800Y549300D02*
X320800D01*
X316100Y544600D01*
X304572D01*
X302665Y546507D01*
Y547006D01*
G01X355739Y568029D02*
X352930D01*
X350337Y565436D01*
Y562120D01*
X341593Y553376D01*
X332728D01*
X329745Y550393D01*
X323893D01*
X322800Y549300D01*
G01X320700Y543250D02*
X323567Y546117D01*
X330094D01*
X331827Y547850D01*
X332667D01*
X332717Y547900D01*
X338239D01*
X351980Y561641D01*
Y564290D01*
X353159Y565469D01*
X355739D01*
G01X302506Y543341D02*
X303047Y542800D01*
X320250D01*
X320700Y543250D01*
G01X336800Y545700D02*
X338983D01*
X351072Y557789D01*
X355739D01*
G01X327403Y543499D02*
X328304Y544400D01*
X330500D01*
X331800Y545700D01*
X336800D01*
G01X336723Y542000D02*
X336831Y542108D01*
X337886D01*
X343582Y547804D01*
X344128D01*
X349422Y553098D01*
G01X355739Y555229D02*
X351553D01*
X349422Y553098D01*
G01X355739Y552669D02*
X353263D01*
X348597Y548003D01*
G01X330200Y531800D02*
X332236Y533836D01*
Y533963D01*
X344577Y546304D01*
X346898D01*
X348597Y548003D01*
G01X336800Y510000D02*
Y512800D01*
X340067Y516067D01*
X351289D01*
X353408Y518186D01*
X361503D01*
X369350Y526033D01*
Y545850D01*
X365091Y550109D01*
X363008D01*
X362997Y550120D01*
X361463D01*
X361452Y550109D01*
X355739D01*
G01X336800Y506300D02*
Y510000D01*
G01X298719Y542538D02*
X298700Y542557D01*
Y549395D01*
X297999Y550096D01*
G01X293050Y551300D02*
X296795D01*
X297999Y550096D01*
G01X322000Y520700D02*
X326200D01*
X327250Y521750D01*
Y526000D01*
G01X309600Y520150D02*
Y520900D01*
X311400Y522700D01*
X314200D01*
X316200Y520700D01*
X322000D01*
G01X347750Y500200D02*
X347200Y500750D01*
X341596D01*
G01D02*
X339465Y502881D01*
X334319D01*
X333400Y503800D01*
G01X286950Y531100D02*
Y527300D01*
G01X290889Y530299D02*
X289405D01*
X288604Y531100D01*
X286950D01*
G01X290889Y530299D02*
X291831D01*
X291991Y530459D01*
X293380D01*
X294100Y531179D01*
X298219D01*
G01X307419Y529209D02*
X312500D01*
X313291Y530000D01*
X316000D01*
G01D02*
X318500D01*
X320000Y531500D01*
Y533750D01*
G01X290889Y535299D02*
X287349D01*
X287050Y535000D01*
G01X290889Y535299D02*
X292388D01*
X294538Y533149D01*
X298219D01*
G01X320000Y537250D02*
X317250D01*
X316000Y536000D01*
G01X324500Y537250D02*
X320000D01*
G01X307419Y531179D02*
X312679D01*
X314651Y533151D01*
Y534651D01*
X316000Y536000D01*
G01X324500Y533750D02*
Y532200D01*
X322900Y530600D01*
G01X351250Y511900D02*
Y507892D01*
X351311Y507831D01*
G01X361439Y515004D02*
X358496D01*
X357000Y516500D01*
X354200D01*
X351250Y513550D01*
Y511900D01*
G01X351300Y504000D02*
Y507820D01*
X351311Y507831D01*
G01X351250Y500200D02*
Y503950D01*
X351300Y504000D01*
G01X299765Y592831D02*
Y596598D01*
X298613Y597750D01*
G01X287600Y597000D02*
X291900D01*
X293100Y598200D01*
X298163D01*
X298613Y597750D01*
G01X361227Y630300D02*
X359827Y631700D01*
X356694D01*
X352180Y636214D01*
G01X347680D02*
Y635214D01*
X354644Y628250D01*
X358550D01*
X359258Y627542D01*
Y623920D01*
G01X352716Y594135D02*
X350867D01*
X349839Y593107D01*
Y589006D01*
X351231Y587614D01*
X352480D01*
G01X357200Y592900D02*
X353951D01*
X352716Y594135D01*
G01X344250Y581000D02*
Y578047D01*
X345525Y576772D01*
X347451D01*
G01D02*
X352376D01*
X353439Y575709D01*
X355739D01*
G01X349373Y571300D02*
X348674Y571999D01*
Y573974D01*
X349537Y574837D01*
X350746D01*
G01X355739Y573149D02*
X353349D01*
X351500Y571300D01*
X349373D01*
G01X323413Y602491D02*
X326938D01*
X331250Y598179D01*
Y596560D01*
G01X299124Y574923D02*
X292132D01*
X292006Y574797D01*
G01X315616Y571817D02*
X316162Y572363D01*
X321324D01*
G01X299124D02*
X292663D01*
X289800Y569500D01*
Y569182D01*
G01X321324Y569803D02*
X317975D01*
X315893Y567721D01*
G01X336003Y576849D02*
X337449D01*
X338200Y577600D01*
X341300D01*
X346577Y572323D01*
Y567339D01*
G01X332503Y576849D02*
X328474D01*
X327874Y576249D01*
G01D02*
X325100Y573475D01*
Y568400D01*
X323943Y567243D01*
X321324D01*
G01X338249Y572721D02*
X341379D01*
X342300Y571800D01*
G01X334749Y572721D02*
X329121D01*
X328200Y571800D01*
G01X338205Y567922D02*
X341325D01*
X341558Y567689D01*
G01X330200Y568100D02*
X334527D01*
X334705Y567922D01*
G01X348116Y594759D02*
X347784Y594327D01*
Y587509D01*
G01X340750Y585500D02*
Y586061D01*
X337811Y589000D01*
X335500D01*
X334500Y590000D01*
Y593500D01*
X335000Y594000D01*
X337750D01*
G01X340750Y585500D02*
X338172D01*
X336923Y586749D01*
G01X337750Y591440D02*
X340560D01*
X342000Y590000D01*
Y587750D01*
X344250Y585500D01*
G01X344616Y594759D02*
Y590187D01*
G01D02*
Y585866D01*
X344250Y585500D01*
G01X318762Y588231D02*
X322326D01*
X325761Y591666D01*
Y592959D01*
G01X315315Y575204D02*
X315596Y574923D01*
X321324D01*
G01X325899Y589186D02*
X322150Y585437D01*
Y583868D01*
X320937Y582655D01*
G01D02*
X320601Y582319D01*
X317046D01*
X316990Y582263D01*
X314694D01*
G01X306766Y582469D02*
X306972Y582263D01*
X311194D01*
G01X304617Y593331D02*
X305969D01*
X308509Y590791D01*
X312262D01*
G01X304617Y593331D02*
X303031D01*
X301551Y591851D01*
Y588186D01*
X300600Y587235D01*
Y585400D01*
X301250Y584750D01*
X304485D01*
X306766Y582469D01*
G01X386000Y485700D02*
Y501306D01*
X388800Y504106D01*
Y509707D01*
X393800Y514707D01*
Y525587D01*
X401416Y533203D01*
Y665251D01*
X394667Y672000D01*
X370600D01*
X365200Y677400D01*
X360617D01*
X356657Y681360D01*
X352100D01*
G01X396400Y659800D02*
X383401D01*
X380701Y662500D01*
X346850D01*
G01D02*
Y670800D01*
X345650Y672000D01*
G01X342542Y685983D02*
X344115Y684410D01*
X345977D01*
G01D02*
X346484D01*
X348554Y686480D01*
X352100D01*
G01X345671Y680190D02*
X346997D01*
X347939Y681132D01*
Y683001D01*
X348858Y683920D01*
X352100D01*
G01X345671Y680190D02*
X344961D01*
X342645Y682506D01*
G01X303279Y670477D02*
X311076D01*
X313477Y672878D01*
X316005D01*
X317534Y674407D01*
X320033D01*
G01X300700Y667000D02*
Y667898D01*
X303279Y670477D01*
G01X330593Y671019D02*
Y672788D01*
X328723Y674658D01*
G01X323533Y674407D02*
Y677051D01*
X324925Y678443D01*
G01X328723Y674658D02*
X328710D01*
X324925Y678443D01*
G01X303741Y648343D02*
Y654095D01*
G01D02*
X303100Y654736D01*
Y658030D01*
G01X299000Y658050D02*
X303080D01*
X303100Y658030D01*
G01X324725Y658350D02*
Y656975D01*
X327780Y653920D01*
X329989D01*
G01X334673Y672886D02*
Y671573D01*
X332100Y669000D01*
X329900D01*
X328600Y667700D01*
Y665850D01*
G01X334673Y677472D02*
Y672886D01*
G01X328600Y665850D02*
X334900D01*
X335425Y666375D01*
X339350D01*
G01X372520Y48200D02*
Y44520D01*
X372500Y44500D01*
G01X372520Y52800D02*
Y56480D01*
X372500Y56500D01*
G01X418487Y71447D02*
X428162Y61772D01*
Y20235D01*
X434005Y14392D01*
X533811D01*
X536219Y16800D01*
X665813D01*
X675903Y26890D01*
Y29541D01*
G01X697305Y28963D02*
X683642Y15300D01*
X536841D01*
X534433Y12892D01*
X431830D01*
X426662Y18060D01*
Y51838D01*
X412800Y65700D01*
Y67600D01*
X380499Y99901D01*
Y245401D01*
X376500Y249400D01*
Y324500D01*
X377300Y325300D01*
Y347800D01*
X382800Y353300D01*
G01X372220Y86300D02*
Y89720D01*
X372500Y90000D01*
G01X372220Y81700D02*
Y78280D01*
X372500Y78000D01*
G01X392800Y491900D02*
Y491500D01*
X388300Y487000D01*
Y478700D01*
X391480Y475520D01*
Y458033D01*
X398700Y450813D01*
Y183789D01*
X408503Y173986D01*
Y108559D01*
X413358Y103704D01*
X430672D01*
X430673Y103703D01*
X432329D01*
X435300Y106674D01*
Y117400D01*
X438077Y120177D01*
Y156805D01*
X435827Y159055D01*
G01X487500Y73400D02*
X484232Y76668D01*
X463603D01*
X458969Y72034D01*
X433821D01*
X419233Y86622D01*
X408113D01*
X389999Y104736D01*
Y189462D01*
X390700Y190163D01*
Y445900D01*
X380200Y456400D01*
Y457800D01*
G01X485700Y70500D02*
X481800Y74400D01*
X464164D01*
X459798Y70034D01*
X432966D01*
X418378Y84622D01*
X407284D01*
X387999Y103907D01*
Y190291D01*
X388650Y190942D01*
Y444950D01*
X376544Y457056D01*
Y460678D01*
G01X428740Y168504D02*
X424990Y164754D01*
Y110394D01*
X424300Y109704D01*
X415845D01*
X414503Y111046D01*
Y176473D01*
X404700Y186276D01*
Y453300D01*
X397688Y460312D01*
Y478712D01*
X397388Y479012D01*
G01X478590Y70310D02*
X467939D01*
X461929Y64300D01*
X432341D01*
X418019Y78622D01*
X407626D01*
X383999Y102249D01*
Y248852D01*
X381400Y251451D01*
Y322600D01*
X383200Y324400D01*
Y339100D01*
X382500Y339800D01*
G01X460800Y66850D02*
X432620D01*
X418848Y80622D01*
X408455D01*
X385999Y103078D01*
Y249681D01*
X384040Y251640D01*
Y322411D01*
X385200Y323571D01*
Y342902D01*
X380799Y347303D01*
G01X435827Y173229D02*
X433300Y170702D01*
Y107503D01*
X431501Y105704D01*
X414187D01*
X410503Y109388D01*
Y174815D01*
X400700Y184618D01*
Y451642D01*
X393480Y458862D01*
Y476349D01*
X390300Y479529D01*
Y486171D01*
X395400Y491271D01*
Y510649D01*
X398300Y513549D01*
Y518900D01*
X397800Y519400D01*
X397650D01*
G01X435827Y178740D02*
X431300Y174213D01*
Y109000D01*
X430004Y107704D01*
X415016D01*
X412503Y110217D01*
Y175644D01*
X402700Y185447D01*
Y452471D01*
X395480Y459691D01*
Y477178D01*
X392300Y480358D01*
Y485342D01*
X400969Y494011D01*
Y520581D01*
X397650Y523900D01*
G01X383600Y473500D02*
X386100Y471000D01*
Y466000D01*
X389350Y462750D01*
Y457334D01*
X396700Y449984D01*
Y187676D01*
X395999Y186975D01*
Y107223D01*
X410600Y92622D01*
X421720D01*
X435907Y78435D01*
X456782D01*
X477190Y98843D01*
Y107649D01*
X466668Y118171D01*
Y156560D01*
X464173Y159055D01*
G01X380113Y480400D02*
X381300Y479213D01*
Y471700D01*
X384100Y468900D01*
Y465171D01*
X385500Y463771D01*
Y457300D01*
X394700Y448100D01*
Y188505D01*
X393999Y187804D01*
Y106394D01*
X409771Y90622D01*
X420891D01*
X435078Y76435D01*
X457611D01*
X479190Y98014D01*
Y108478D01*
X468668Y119000D01*
Y160072D01*
X464173Y164567D01*
G01X535039Y173229D02*
X537289Y170979D01*
Y119997D01*
X516001Y98709D01*
X498208D01*
X478167Y78668D01*
X462774D01*
X458140Y74034D01*
X434650D01*
X420062Y88622D01*
X408942D01*
X391999Y105565D01*
Y188633D01*
X392700Y189334D01*
Y447129D01*
X391200Y448629D01*
G01X418487Y71447D02*
X413312Y76622D01*
X406797D01*
X381999Y101420D01*
Y246023D01*
X378000Y250022D01*
Y323214D01*
X380600Y325814D01*
Y335700D01*
G01X365931Y225861D02*
Y220531D01*
X361424Y216024D01*
X361383D01*
X360300Y214941D01*
Y207224D01*
X363975Y203549D01*
G01X363682Y185174D02*
Y178017D01*
X361509Y175844D01*
G01X360382Y190150D02*
X366150D01*
X366300Y190000D01*
G01D02*
X366425Y189875D01*
Y187917D01*
X363682Y185174D01*
G01X356611Y199968D02*
Y198528D01*
X356571Y198488D01*
Y192429D01*
X358850Y190150D01*
X360382D01*
G01X374883Y181103D02*
Y177180D01*
X374890Y177173D01*
G01X369009Y171969D02*
X369686D01*
X374890Y177173D01*
G01X363100Y220900D02*
Y219863D01*
X358800Y215563D01*
Y201100D01*
X363600Y196300D01*
X367250D01*
X368350Y195200D01*
Y192364D01*
X370650Y190064D01*
G01X369009Y179719D02*
Y184842D01*
X370650Y186483D01*
Y190064D01*
G01X370730Y241308D02*
Y245508D01*
G01X369095Y210049D02*
Y219073D01*
X373000Y222978D01*
Y243238D01*
X370730Y245508D01*
G01X369882Y225923D02*
X365993D01*
X365931Y225861D01*
G01X365125Y233565D02*
X368935D01*
X369882Y232618D01*
Y225923D01*
G01X358050Y254056D02*
Y254064D01*
X362759Y258773D01*
Y351927D01*
X376910Y366078D01*
G01X377300Y362700D02*
X364759Y350159D01*
Y257649D01*
X362349Y255239D01*
G01X373700Y329700D02*
X372759Y328759D01*
Y246741D01*
X374500Y245000D01*
Y211200D01*
X370645Y207345D01*
Y207338D01*
X370206Y206899D01*
X367984D01*
X367983Y206900D01*
X367400D01*
X366535Y207765D01*
Y210049D01*
G01X363100Y220900D02*
Y222631D01*
X362431Y223300D01*
Y225861D01*
G01X382500Y339800D02*
Y342418D01*
X381009Y343909D01*
G01X390651Y499000D02*
X392800Y496851D01*
Y491900D01*
G01X381400Y462000D02*
X377300D01*
X376544Y461244D01*
Y460678D01*
G01X364275Y486275D02*
X368400Y490400D01*
X376171D01*
X377760Y491989D01*
Y502260D01*
X382300Y506800D01*
Y508300D01*
X381501Y509099D01*
X377739D01*
G01X359481Y484416D02*
X362416D01*
X364275Y486275D01*
G01X359481Y484416D02*
X359552Y484345D01*
Y480368D01*
G01X387950Y466800D02*
X388500Y467350D01*
Y473188D01*
X386000Y475688D01*
Y485700D01*
G01X397388Y479012D02*
X394700Y481700D01*
G01X356502Y474400D02*
Y492866D01*
X362500Y498864D01*
Y499970D01*
G01X377691Y451891D02*
X374500Y455082D01*
Y457800D01*
X361650Y470650D01*
X357850D01*
X356502Y471998D01*
Y474400D01*
G01X396300Y587000D02*
X399416Y583884D01*
Y545716D01*
X394000Y540300D01*
Y528672D01*
X391800Y526472D01*
Y515536D01*
X386800Y510536D01*
Y504935D01*
X383400Y501535D01*
Y473700D01*
X383600Y473500D01*
G01X396400Y583500D02*
X397416Y582484D01*
Y554016D01*
X392000Y548600D01*
Y529501D01*
X389800Y527301D01*
Y516365D01*
X384800Y511365D01*
Y505764D01*
X381300Y502264D01*
Y481587D01*
X380113Y480400D01*
G01X381370Y465500D02*
X382100Y464770D01*
Y464342D01*
X383500Y462942D01*
Y456400D01*
X391200Y448700D01*
Y448629D01*
G01D02*
X391129D01*
G01X391700Y507300D02*
Y504177D01*
X388123Y500600D01*
Y492432D01*
G01X364211Y475491D02*
X361376D01*
X361013Y475128D01*
G01X367711Y475491D02*
X369320Y477100D01*
X370500D01*
X372300Y478900D01*
G01D02*
Y480939D01*
X371839Y481400D01*
Y484339D01*
X372700Y485200D01*
Y487250D01*
G01X370140D02*
X368786D01*
X367552Y486016D01*
Y480084D01*
G01D02*
X367436Y479968D01*
X363452D01*
X363052Y480368D01*
G01X375260Y493750D02*
Y495104D01*
X367050Y503314D01*
Y505967D01*
X370508Y509425D01*
Y522108D01*
X372558Y524158D01*
Y538358D01*
X372900Y538700D01*
G01X385600Y537300D02*
X385500Y537400D01*
X384100D01*
X383300Y536600D01*
Y535300D01*
X380881Y532881D01*
X379088D01*
G01X385750Y533400D02*
Y537150D01*
X385600Y537300D01*
G01X384400Y545195D02*
Y548250D01*
X384300Y548350D01*
G01D02*
X382350D01*
X381549Y547549D01*
X377939D01*
G01X388489Y555985D02*
Y559584D01*
X387517Y560556D01*
G01D02*
X386350Y561723D01*
Y564400D01*
G01X377939Y568029D02*
X381670D01*
X382687Y567012D01*
X383893D01*
X386350Y564555D01*
Y564400D01*
G01X387800Y525500D02*
X385755D01*
X383374Y527881D01*
X379088D01*
G01X387700Y521600D02*
X384755D01*
X383474Y522881D01*
X379088D01*
G01X377739Y513039D02*
X381293D01*
X382300Y514046D01*
Y518400D01*
X381100Y519600D01*
X376808D01*
X375088Y521320D01*
Y543288D01*
X376617Y544817D01*
G01X377939Y565469D02*
X374859D01*
X363484Y554094D01*
X362776D01*
X362280Y554590D01*
G01X368900Y505000D02*
X372200D01*
X374334Y507134D01*
X377739D01*
G01Y515004D02*
X374478D01*
X372494Y513020D01*
G01X364900Y581500D02*
Y577944D01*
X367845Y574999D01*
Y569445D01*
X365525Y567125D01*
X364625D01*
X360409Y562909D01*
X355739D01*
G01X366500Y586300D02*
X367100Y585700D01*
Y577866D01*
X370249Y574717D01*
Y564449D01*
X366149Y560349D01*
X355739D01*
G01X388750Y675600D02*
X393896D01*
X403416Y666080D01*
Y532374D01*
X395800Y524758D01*
Y513878D01*
X391700Y509778D01*
Y507300D01*
G01X370763Y547900D02*
X372500D01*
X374709Y550109D01*
X377939D01*
G01X370800Y551300D02*
X372169Y552669D01*
X377939D01*
G01X370800Y554700D02*
X372000D01*
X372529Y555229D01*
X377939D01*
G01X383080Y554897D02*
Y554940D01*
X380231Y557789D01*
X377939D01*
G01X384347Y558647D02*
X382153D01*
X380451Y560349D01*
X377939D01*
G01X382922Y561735D02*
X381748Y562909D01*
X377939D01*
G01X361439Y507134D02*
X364681D01*
X365900Y508353D01*
Y514700D01*
X365596Y515004D01*
X361439D01*
G01X361120Y589136D02*
X362632D01*
X364300Y590804D01*
Y592900D01*
G01X356680Y589114D02*
X361098D01*
X361120Y589136D01*
G01X364300Y592900D02*
Y593194D01*
X363195Y594299D01*
Y601320D01*
G01X387750Y613900D02*
Y610850D01*
X386400Y609500D01*
G01X387750Y613900D02*
X387650Y613800D01*
X384300D01*
X383511Y614589D01*
X376464D01*
G01X386400Y609500D02*
Y606550D01*
X387550Y605400D01*
X389550D01*
G01X384500Y616500D02*
X384443Y616557D01*
X376464D01*
G01X384500Y616500D02*
X386306D01*
X387786Y617980D01*
G01X365164Y601320D02*
Y595427D01*
X366618Y593973D01*
X367133D01*
X369100Y592006D01*
G01D02*
X370220Y590886D01*
Y586586D01*
G01X361227Y623920D02*
X361351Y624044D01*
Y630176D01*
X361227Y630300D01*
G01X357200Y592900D02*
X358552D01*
X361227Y595575D01*
Y601320D01*
G01X374522Y591597D02*
X369101Y597018D01*
Y601320D01*
G01X374522Y591597D02*
Y586928D01*
X374600Y586850D01*
G01X378800Y583850D02*
X377600D01*
X374600Y586850D01*
G01X373038Y600970D02*
Y598784D01*
X377022Y594800D01*
X378400D01*
G01X383500Y588800D02*
X387220Y585080D01*
X389486D01*
G01X378400Y594800D02*
X380700D01*
X383500Y592000D01*
Y588800D01*
G01X389550Y597200D02*
Y593300D01*
X389450Y593200D01*
G01X383400Y598800D02*
X384400Y597800D01*
X388950D01*
X389550Y597200D01*
G01X383400Y598800D02*
X380339Y601861D01*
Y605782D01*
X379407Y606714D01*
X376464D01*
G01X362614Y635920D02*
X363195Y635339D01*
Y623920D01*
G01X362536Y639880D02*
X362614Y639802D01*
Y635920D01*
G01X365164Y623920D02*
Y632764D01*
X366114Y633714D01*
Y635920D01*
G01D02*
Y639270D01*
X366664Y639820D01*
G01X383000Y583850D02*
Y584500D01*
X379100Y588400D01*
G01D02*
X377100Y590400D01*
Y592600D01*
X375000Y594700D01*
X374370D01*
X371070Y598000D01*
Y601320D01*
G01X376814Y604746D02*
Y601736D01*
X384025Y594525D01*
G01D02*
X389450Y589100D01*
G01X389550Y601300D02*
X387100D01*
X383500Y604900D01*
G01D02*
X379717Y608683D01*
X376464D01*
G01Y618526D02*
X380059D01*
X383313Y621780D01*
G01D02*
X383798Y622265D01*
X389131D01*
G01X389150Y637900D02*
Y633850D01*
X388700Y633400D01*
G01X373038Y624270D02*
X377970D01*
X384600Y630900D01*
X386200D01*
X388700Y633400D01*
G01X384200Y626000D02*
X382200Y624000D01*
X381600D01*
X378094Y620494D01*
X376814D01*
G01X384200Y626000D02*
X386780Y628580D01*
X389186D01*
G01X365953Y570753D02*
X365353D01*
X363100Y568500D01*
X360700D01*
X358611Y570589D01*
X355739D01*
G01X382600Y609000D02*
X382295D01*
X380644Y610651D01*
X376464D01*
G01X384495Y569100D02*
X383006Y570589D01*
X377939D01*
G01X384495Y569100D02*
X387476D01*
X388145Y568431D01*
G01X388194Y572999D02*
X387854Y573339D01*
X383944D01*
G01D02*
X383754Y573149D01*
X377939D01*
G01X392631Y622265D02*
Y623469D01*
X390600Y625500D01*
G01X366100Y590000D02*
Y589100D01*
X363750Y586750D01*
Y584104D01*
X364900Y582954D01*
Y581500D01*
G01X395127Y568056D02*
X394752Y568431D01*
X391645D01*
G01X395100Y572899D02*
X395000Y572999D01*
X391694D01*
G01X360049Y645871D02*
X362536Y643384D01*
Y639880D01*
G01X366664Y639820D02*
Y642569D01*
X365614Y643619D01*
Y650624D01*
X366817Y651827D01*
X369273D01*
G01X388850Y683900D02*
X392100D01*
G01X388750Y679800D02*
X392000D01*
G01X374300Y683920D02*
X378400D01*
X378576Y684096D01*
X380700D01*
G01D02*
X382100D01*
X382296Y683900D01*
X385350D01*
G01X385250Y679800D02*
X380800D01*
G01D02*
X380260D01*
X378700Y681360D01*
X374300D01*
G01X385250Y675600D02*
X380800D01*
G01D02*
X380600D01*
X377400Y678800D01*
X374300D01*
G01X366800Y702960D02*
X373060D01*
G01X389552Y694223D02*
Y691729D01*
X390355Y690926D01*
G01X374300Y694160D02*
X381502D01*
X381593Y694069D01*
G01D02*
X385898D01*
X386052Y694223D01*
G01X472800Y50000D02*
X470953Y48153D01*
Y45150D01*
G01X469000Y50100D02*
X469100Y50000D01*
Y49600D01*
X468984Y49484D01*
Y45150D01*
G01X450900Y29000D02*
X453121D01*
X454600Y30479D01*
X458250D01*
G01X450900Y29000D02*
X449779D01*
X448300Y30479D01*
X446157D01*
X446135Y30457D01*
G01X450900Y24000D02*
X451800D01*
X456310Y28510D01*
X457950D01*
G01X446135Y26157D02*
X447543D01*
X449700Y24000D01*
X450900D01*
G01X458041Y47341D02*
X460659D01*
X461110Y46890D01*
Y45450D01*
G01X472336Y53022D02*
X474400Y55086D01*
Y56600D01*
G01X472336Y53022D02*
X474850Y50508D01*
Y48750D01*
X472921Y46821D01*
Y45150D01*
G01X474400Y56600D02*
Y59200D01*
X472700Y60900D01*
Y61150D01*
G01X468400Y61250D02*
Y59600D01*
X468800Y59200D01*
Y57000D01*
G01X468836Y53022D02*
X467297Y51483D01*
Y50494D01*
X467016Y50213D01*
Y45150D01*
G01X468800Y57000D02*
Y53058D01*
X468836Y53022D01*
G01X472700Y64650D02*
X473650D01*
X476100Y62200D01*
Y60500D01*
G01X478700Y62800D02*
Y64580D01*
X477129Y66151D01*
G01X462372Y49179D02*
X463079Y48472D01*
Y45150D01*
G01X485585Y34890D02*
X481932D01*
X481458Y34416D01*
X477750D01*
G01X486400Y38500D02*
X486500Y38600D01*
X489150D01*
X489750Y38000D01*
G01X485585Y34890D02*
X486400Y35705D01*
Y38500D01*
G01X467016Y25650D02*
Y20430D01*
G01X437635Y38057D02*
Y41066D01*
X439057Y42488D01*
G01D02*
X441241D01*
X441378Y42351D01*
X443489D01*
G01X451231Y41843D02*
X454721Y38353D01*
X458250D01*
G01X443489Y42351D02*
X450723D01*
X451231Y41843D01*
G01X450454Y38147D02*
X446066D01*
G01X450454D02*
X451081D01*
X452238Y36990D01*
X452310D01*
X452916Y36384D01*
X458250D01*
G01X489750Y42000D02*
X486588D01*
X486527Y41939D01*
G01D02*
X486139D01*
X480589Y36389D01*
X480395D01*
X480390Y36384D01*
X477750D01*
G01X450832Y50121D02*
X449665D01*
X447423Y52363D01*
X444559D01*
X443457Y53465D01*
G01X439046Y51800D02*
Y55891D01*
X439308Y56153D01*
G01D02*
X440769D01*
X443457Y53465D01*
G01X457950Y42290D02*
Y44631D01*
X452460Y50121D01*
X450832D01*
G01X478050Y28510D02*
X480540D01*
X480571Y28479D01*
X482021D01*
X483000Y27500D01*
X485300D01*
G01D02*
X487250D01*
X489750Y30000D01*
G01X453400Y19100D02*
X457242D01*
X461110Y22968D01*
Y25350D01*
G01X453400Y19100D02*
X451100D01*
X448243Y21957D01*
X446035D01*
G01X474890Y45450D02*
Y46990D01*
X477171Y49271D01*
Y51517D01*
G01X479476Y59562D02*
Y55778D01*
G01D02*
Y55462D01*
X477171Y53157D01*
Y51517D01*
G01X496678Y61151D02*
X493053D01*
X489178Y65026D01*
G01X482976Y59562D02*
Y63279D01*
X483347Y63650D01*
G01X489264Y51841D02*
X492953D01*
X493238Y52126D01*
G01X489178Y57276D02*
X492523D01*
X493238Y56561D01*
Y52126D01*
G01X446085Y34357D02*
X446144Y34416D01*
X450200D01*
G01D02*
X452055D01*
X452087Y34384D01*
X454102D01*
X454134Y34416D01*
X458250D01*
G01Y40321D02*
X456417D01*
X451481Y45257D01*
X448226D01*
G01X443489Y45851D02*
Y49933D01*
X443457Y49965D01*
G01X439055Y47144D02*
X441812Y49901D01*
Y49965D01*
X443457D01*
G01X448226Y45257D02*
X446345D01*
X445751Y45851D01*
X443489D01*
G01X443457Y49965D02*
X446097D01*
X447233Y48829D01*
G01X484513Y22548D02*
X481779D01*
X478977Y25350D01*
X474890D01*
G01X484513Y22548D02*
X485337D01*
X488789Y26000D01*
X489750D01*
G01X472921Y25650D02*
Y22073D01*
X476890Y18104D01*
X481353D01*
G01D02*
X483975D01*
X487671Y21800D01*
X489650D01*
G01X493250Y26000D02*
X496355D01*
G01X493150Y21800D02*
X495755D01*
X496242Y22287D01*
G01X490150Y34000D02*
X489600D01*
X486700Y31100D01*
G01X477750Y30479D02*
X483279D01*
X483900Y31100D01*
X486700D01*
G01X477129Y66151D02*
X476480Y66800D01*
X468800D01*
X468400Y66400D01*
Y64750D01*
G01X489178Y65026D02*
X484723D01*
X483347Y63650D01*
G01X442913Y154331D02*
X442408D01*
X439577Y151500D01*
Y116823D01*
X445100Y111300D01*
Y110000D01*
X456750Y98350D01*
X460446D01*
X462874Y95922D01*
G01X482200Y70500D02*
X480300Y72400D01*
X467200D01*
X461650Y66850D01*
X460800D01*
G01X498500Y84200D02*
X510200D01*
X520709Y94709D01*
X534468D01*
X553711Y113952D01*
Y160068D01*
X549212Y164567D01*
G01X471281Y105681D02*
X470419D01*
X461565Y114535D01*
X455766D01*
G01X473600Y108300D02*
X471491D01*
X461991Y117800D01*
X457000D01*
G01X513779Y168504D02*
X510202Y164927D01*
Y121758D01*
X498602Y110158D01*
X482451D01*
X480538Y112071D01*
G01X448996Y117666D02*
X447300Y119362D01*
Y156355D01*
X450000Y159055D01*
G01X463479Y99412D02*
X461788D01*
X459237Y101963D01*
X455309D01*
X447362Y109910D01*
Y113738D01*
X445602Y115498D01*
Y165815D01*
X442913Y168504D01*
G01X527547Y50148D02*
X526797Y50898D01*
X523300D01*
X523301Y50899D01*
G01D02*
X519493D01*
G01X515700D02*
X519493D01*
G01X527550Y54648D02*
X523550D01*
X523301Y54399D01*
G01D02*
X521986Y55714D01*
X519517D01*
G01D02*
X515947D01*
X515785Y55552D01*
G01X531050Y50148D02*
Y46998D01*
G01X531047Y50148D02*
X531050D01*
G01D02*
X532900D01*
X535103Y47945D01*
X536993D01*
G01X528300Y58648D02*
X531050Y55898D01*
Y54648D01*
G01D02*
X531347Y54351D01*
X536993D01*
G01X543059Y108958D02*
X546356Y112255D01*
Y169786D01*
X542126Y174016D01*
G01X540800Y111500D02*
X544856Y115556D01*
Y167041D01*
X543393Y168504D01*
X542126D01*
G01X501100Y86800D02*
X506800D01*
X516709Y96709D01*
X533639D01*
X551711Y114781D01*
Y156556D01*
X549212Y159055D01*
G01X513300Y83000D02*
Y84200D01*
X520408Y91308D01*
X542281D01*
X559073Y108100D01*
Y151557D01*
X556299Y154331D01*
G01X503700Y107600D02*
Y110700D01*
X511632Y118632D01*
X516908D01*
X524397Y126121D01*
Y150775D01*
X527953Y154331D01*
G01X703300Y21750D02*
X695544D01*
G01X710550Y30775D02*
X703975D01*
X703300Y30100D01*
G01Y25250D02*
Y30100D01*
G01X723800Y33150D02*
X701492D01*
X697305Y28963D01*
G01X714454Y406785D02*
Y400454D01*
X713200Y399200D01*
G01Y394250D02*
Y399200D01*
G01Y390750D02*
Y387700D01*
G01X716100Y435350D02*
X712000D01*
G01X712851Y478332D02*
Y483089D01*
G01Y478332D02*
X711700D01*
X709700Y480332D01*
G01X712851Y483089D02*
Y494650D01*
X712205Y495296D01*
Y501279D01*
G01X734761Y470838D02*
X721433D01*
X706095Y455500D01*
X697300D01*
X694785Y458015D01*
X693815D01*
X683000Y447200D01*
G01X680200Y449500D02*
Y454283D01*
X686717Y460800D01*
X695700D01*
X698485Y458015D01*
X704744D01*
X710633Y463904D01*
G01X718110Y501279D02*
Y495218D01*
X716064Y493172D01*
Y469335D01*
X710633Y463904D01*
G01X705700Y493500D02*
X708268Y496068D01*
Y501279D01*
G01X708367Y491000D02*
Y493338D01*
X710268Y495239D01*
Y497622D01*
X710236Y497654D01*
Y501279D01*
G01X653796Y521683D02*
X656827D01*
X656846Y521702D01*
G01X653833Y525811D02*
Y521720D01*
X653796Y521683D01*
G01X650333Y530195D02*
X646694D01*
X644559Y528060D01*
G01X650333Y525811D02*
X646808D01*
X644559Y528060D01*
G01X669882Y531004D02*
Y533724D01*
X669348Y534258D01*
X658474D01*
X657481Y533265D01*
X651644D01*
X650333Y531954D01*
Y530195D01*
G01X678740Y508760D02*
X672540Y514960D01*
X659728D01*
X657128Y517560D01*
G01X678740Y501279D02*
Y508760D01*
G01X729900Y26900D02*
X726550D01*
X723800Y29650D01*
G01X729900Y26900D02*
X732328D01*
X735800Y23428D01*
X761811D01*
X766683Y28300D01*
X771900D01*
X772600Y29000D01*
Y31535D01*
G01Y23465D02*
Y26160D01*
X772060Y26700D01*
X767205D01*
X762433Y21928D01*
X731437D01*
G01D02*
X727322D01*
X723800Y25450D01*
G01X718050Y26900D02*
X722350D01*
X723800Y25450D01*
G01X718300Y394250D02*
Y399100D01*
X718200Y399200D01*
G01X717014Y406785D02*
Y400386D01*
X718200Y399200D01*
G01X724200Y398380D02*
X719574Y403006D01*
Y406785D01*
G01X718300Y390750D02*
Y387700D01*
G01X717014Y422965D02*
Y429586D01*
X716100Y430500D01*
G01Y435350D02*
Y430500D01*
G01X719574Y422965D02*
Y428974D01*
X721100Y430500D01*
G01Y435350D02*
Y430500D01*
G01Y435350D02*
X725200D01*
G01X733750Y426800D02*
Y431000D01*
G01X722134Y422965D02*
Y425334D01*
X723600Y426800D01*
X728900D01*
G01D02*
X733750D01*
G01X720017Y478664D02*
Y483158D01*
G01D02*
X720014Y483161D01*
Y501214D01*
X720079Y501279D01*
G01X734761Y470838D02*
X802862D01*
X806300Y467400D01*
X814000D01*
X816535Y469935D01*
Y501279D01*
G01X741000Y547700D02*
Y544500D01*
X733090Y536590D01*
Y512557D01*
X725984Y505451D01*
Y501279D01*
G01X740900Y553600D02*
X738700Y551400D01*
Y546953D01*
X731290Y539543D01*
Y513057D01*
X724016Y505783D01*
Y501279D01*
G01X768307Y531004D02*
Y534637D01*
X765935Y537009D01*
G01X777165Y509835D02*
X772000Y515000D01*
X759500D01*
X754800Y519700D01*
Y526950D01*
G01X777165Y501279D02*
Y509835D01*
G01X846077Y152174D02*
X842022D01*
G01X799914Y421965D02*
Y428586D01*
X799000Y429500D01*
G01X802474Y421965D02*
Y427974D01*
X804000Y429500D01*
G01X805034Y421965D02*
Y424334D01*
X806500Y425800D01*
X811800D01*
G01X807100Y397380D02*
X802474Y402006D01*
Y405785D01*
G01X799914D02*
Y399386D01*
X801100Y398200D01*
G01X801200Y393250D02*
Y398100D01*
X801100Y398200D01*
G01X797354Y405785D02*
Y399454D01*
X796100Y398200D01*
G01Y393250D02*
Y398200D01*
G01X801200Y389750D02*
Y386700D01*
G01X796100Y389750D02*
Y386700D01*
G01X860208Y373756D02*
Y370108D01*
X850730Y360630D01*
Y357528D01*
G01X846456Y357507D02*
X850709D01*
X850730Y357528D01*
G01X846456Y357507D02*
X843209D01*
X842916Y357214D01*
G01X853060Y407748D02*
X849420D01*
G01X799000Y434350D02*
Y429500D01*
G01Y434350D02*
X794900D01*
G01X804000D02*
X808100D01*
G01X804000D02*
Y429500D01*
G01X816650Y425800D02*
Y430000D01*
G01X811800Y425800D02*
X816650D01*
G01X811099Y477229D02*
Y481767D01*
G01Y477229D02*
X807400D01*
G01X811099Y481767D02*
Y494198D01*
X810630Y494667D01*
Y501279D01*
G01X823728Y477050D02*
Y481512D01*
G01D02*
Y488672D01*
X818504Y493896D01*
Y501279D01*
G01X824409D02*
Y494430D01*
X835949Y482890D01*
G01X822441Y501279D02*
Y492393D01*
X830426Y484408D01*
Y482939D01*
G01X803300Y491600D02*
Y493400D01*
X806693Y496793D01*
Y501279D01*
G01X806888Y491398D02*
Y493788D01*
X808661Y495561D01*
Y501279D01*
G54D11*
X38500Y53200D03*
X48200Y678984D03*
X78268Y63455D03*
X104000Y482200D03*
X108500Y490700D03*
X104000D03*
X108277Y574051D03*
X86028Y693139D03*
X81928Y693239D03*
X111200Y713300D03*
X174588Y493113D03*
X187167Y506384D03*
X198700Y520300D03*
X203500D03*
X212600Y520400D03*
X141914Y523238D03*
X182648Y506454D03*
X142572Y637132D03*
X150872D03*
X166500Y637200D03*
X157458Y637232D03*
X145279Y622570D03*
X172700Y626100D03*
X176800D03*
X180985D03*
X185085D03*
X189185D03*
X193285D03*
X149400Y626600D03*
X204100Y641400D03*
X154300Y706915D03*
X168047Y708475D03*
X151749Y699115D03*
X164249D03*
X210123Y658996D03*
X267514Y543985D03*
X243700Y555500D03*
X229342Y518355D03*
X238000Y625200D03*
X234000D03*
X221900Y627100D03*
X229952Y629830D03*
X225900Y627100D03*
X251900Y616800D03*
X243900D03*
X262823Y628096D03*
X236000Y642600D03*
X223400Y641400D03*
X225984Y662443D03*
X258431Y708224D03*
X246700Y679300D03*
X247500Y705700D03*
X214723Y655496D03*
X343582Y181878D03*
X347882Y274478D03*
X346819Y524075D03*
X350400Y531900D03*
X341226Y531909D03*
X334827Y520553D03*
X304617Y593281D03*
X299000Y661500D03*
X289612Y664929D03*
X291700Y733600D03*
X287620Y733620D03*
X374883Y184553D03*
X359481Y487866D03*
X384300Y551800D03*
X361120Y589086D03*
X374600Y586800D03*
X464342Y57258D03*
X443489Y45801D03*
X468400Y64700D03*
X472700Y64600D03*
X594541Y32981D03*
X590347Y60707D03*
X703300Y25200D03*
X713200Y394200D03*
X712851Y478282D03*
X712000Y438800D03*
X718300Y394200D03*
X725200Y438800D03*
X754800Y530400D03*
X854596Y162535D03*
X841625Y181177D03*
X846077Y155624D03*
X838627Y382215D03*
X846456Y357457D03*
X834984Y374469D03*
X796100Y393200D03*
X801200D03*
X811099Y477179D03*
X794900Y437800D03*
X808100D03*
G54D122*
X849018Y192564D03*
G54D113*
X646021Y42707D03*
X630273D03*
G54D104*
X536993Y54351D03*
Y47945D03*
G54D20*
G01X-36569Y-23804D02*
Y-103804D01*
G01D02*
X1258031D01*
G01X-40569Y-7804D02*
G02I-12000J0D01*
G01X-45719D02*
G02I-6850J0D01*
G01X-52569Y-23804D02*
Y8196D01*
G01X-36569Y-23804D02*
X1258031D01*
G01X-36569Y-59304D02*
X1258031D01*
G01X-36569Y-7804D02*
X-68569D01*
G01X55250Y45000D02*
Y25458D01*
X56102Y24606D01*
G01X51000Y52000D02*
Y49250D01*
X55250Y45000D01*
G01X51000Y52000D02*
Y59500D01*
G01X43000Y54500D02*
Y59500D01*
G01X34000Y54500D02*
Y59400D01*
G01X38500Y53250D02*
Y56500D01*
G01X44156Y532622D02*
X53524D01*
G01X52613Y538242D02*
X52606Y538249D01*
X44256D01*
G01Y543876D02*
X52408D01*
G01X52603Y549526D02*
X52577Y549500D01*
X44050D01*
G01X52485Y555153D02*
X44237D01*
G01X41502Y659909D02*
X37961D01*
G01X64796Y647850D02*
Y650896D01*
X64884Y650984D01*
G01X44734Y671800D02*
X41100D01*
G01X48200Y679034D02*
X53066D01*
X56100Y676000D01*
G01X90768Y69755D02*
Y62255D01*
G01D02*
Y59505D01*
X95018Y55255D01*
G01D02*
X95068Y55205D01*
Y42727D01*
X103346Y34449D01*
G01X78268Y63505D02*
Y66755D01*
G01X82768Y64755D02*
Y69755D01*
G01X73768Y64755D02*
Y69655D01*
G01X104000Y478750D02*
Y475500D01*
G01X123586Y490300D02*
X118197D01*
G01X108500Y478750D02*
Y475500D01*
G01X93531Y492891D02*
X97074D01*
G01X135012Y514552D02*
Y510200D01*
G01X119300Y514850D02*
Y511600D01*
X119400Y511500D01*
G01X137017Y537795D02*
X136974Y537752D01*
Y534479D01*
G01X101100Y511850D02*
X105350D01*
G01X126950Y530300D02*
X123300D01*
G01X125788Y521048D02*
X123848D01*
X121150Y518350D01*
X119300D01*
G01D02*
Y521600D01*
X119400Y521700D01*
G01X92000Y517450D02*
Y521409D01*
X92286Y521695D01*
G01X86659Y517527D02*
Y521695D01*
G01X81032Y517527D02*
Y521695D01*
G01X75405Y517527D02*
Y521695D01*
G01X69778Y517527D02*
Y521695D01*
G01X101113Y522827D02*
X99045D01*
X97913Y521695D01*
G01X85400Y634966D02*
Y629784D01*
G01X108277Y574101D02*
Y575990D01*
X108305Y576018D01*
Y577192D01*
X108371Y577258D01*
G01X118900Y609900D02*
Y610600D01*
X118353Y611147D01*
Y613818D01*
G01X116400Y626600D02*
X117650Y625350D01*
X119600D01*
G01X123250Y599000D02*
Y601350D01*
X118900Y605700D01*
Y609900D01*
G01X98454Y647050D02*
X104550D01*
G01X98454Y639150D02*
X104850D01*
G01X115619Y706995D02*
X112795D01*
X111300Y705500D01*
G01X73427Y695785D02*
Y699285D01*
G01X86028Y696439D02*
Y693189D01*
G01X81928Y693289D02*
Y697539D01*
G01X143867Y740048D02*
X143834Y740015D01*
X139000D01*
G01X132651D02*
X139000D01*
G01X182587Y463761D02*
X186254D01*
G01X182513Y469880D02*
X186982D01*
X188708Y468154D01*
G01X175115Y463761D02*
X179087D01*
G01X184924Y493198D02*
Y497324D01*
X185615Y498015D01*
G01X208650Y495300D02*
X208500Y495150D01*
Y491700D01*
X208370Y491570D01*
G01X162144Y465300D02*
X167656D01*
G01X182513Y459780D02*
X187380D01*
X189700Y462100D01*
Y463500D01*
G01X212600Y516950D02*
Y514400D01*
X211700Y513500D01*
G01X191400Y505850D02*
Y509000D01*
X191398D01*
G01X203350Y506700D02*
Y503300D01*
G01X198700Y516850D02*
Y513500D01*
G01X215750Y512066D02*
X213134D01*
X211700Y513500D01*
G01X212000Y502750D02*
X207838D01*
X207500Y502412D01*
G01X170700Y513600D02*
X170380Y513920D01*
Y516950D01*
G01D02*
X166280D01*
G01X182870Y513832D02*
X184438D01*
X186537Y515931D01*
G01X182474Y517241D02*
Y514228D01*
X182870Y513832D01*
G01X142000Y512050D02*
Y508590D01*
X141980D01*
G01X185615Y498015D02*
X187167Y499567D01*
Y502934D01*
G01X182648Y503004D02*
X178104D01*
X174900Y499800D01*
G01X146242Y515686D02*
Y513158D01*
X146900Y512500D01*
G01X146242Y519686D02*
Y515686D01*
G01X211700Y634100D02*
X213700Y632100D01*
Y632000D01*
X214500Y631200D01*
X215800D01*
G01X166500Y637250D02*
Y640300D01*
G01X208250Y626900D02*
X205300D01*
X203300Y628900D01*
G01X142572Y637182D02*
Y640332D01*
G01X150872Y637182D02*
Y640332D01*
G01X159058Y641132D02*
X157458Y639532D01*
Y637282D01*
G01X197087Y679921D02*
X191767D01*
X191766Y679920D01*
G01X151749Y695665D02*
X148349D01*
X148249Y695765D01*
G01X154300Y703465D02*
X151130D01*
Y703440D01*
G01X188078Y643963D02*
X184807D01*
G01X211706Y641442D02*
Y645349D01*
G01X215406Y641442D02*
X211706D01*
G01X207900Y641450D02*
X208200Y641750D01*
Y645500D01*
G01X205827Y688956D02*
Y695000D01*
G01X188600Y696800D02*
X188500Y696700D01*
Y693550D01*
G01X155849Y695665D02*
X157874D01*
X158994Y694545D01*
G01X210123Y659046D02*
Y662100D01*
G01X204100Y646500D02*
Y641450D01*
G01X158599Y711215D02*
X162100D01*
G01X275300Y467300D02*
X273400Y465400D01*
X271850D01*
G01X221225Y490300D02*
X227100D01*
G01X271850Y489500D02*
X274900D01*
X275700Y490300D01*
G01X271450Y470300D02*
X273000D01*
X275100Y472400D01*
G01X259079Y465300D02*
X262700D01*
X264800Y467400D01*
G01D02*
X266800Y465400D01*
X268350D01*
G01X278800Y467500D02*
Y462500D01*
X274500Y458200D01*
X271450D01*
G01X237813Y539142D02*
X235959D01*
X234648Y540453D01*
G01X279600Y527900D02*
X282800Y531100D01*
X283450D01*
G01Y527300D02*
Y522900D01*
X283550Y522800D01*
G01X287500Y518000D02*
Y518100D01*
X283550Y522050D01*
Y522800D01*
G01X272375Y541121D02*
Y537775D01*
X272100Y537500D01*
G01X251346Y554100D02*
Y556961D01*
X251446Y557061D01*
G01X256816Y563982D02*
X256370D01*
X255456Y563068D01*
X251527D01*
G01X254175Y567260D02*
Y566623D01*
X256816Y563982D01*
G01X283600Y539294D02*
X290145D01*
G01X243700Y552050D02*
Y549600D01*
X242700Y548600D01*
G01X248878Y536660D02*
X249460D01*
X252400Y539600D01*
G01X263950Y553100D02*
X262996Y552146D01*
Y548757D01*
G01X264358Y608152D02*
Y619252D01*
X267421Y622315D01*
X270300D01*
G01D02*
X287085D01*
X290500Y618900D01*
Y609600D01*
X285700Y604800D01*
X277500D01*
X274800Y607500D01*
G01X238000Y625250D02*
X234000D01*
G01D02*
Y628400D01*
G01X250475Y633776D02*
X252523D01*
X255228Y631071D01*
G01X250824Y629614D02*
X253771D01*
X255228Y631071D01*
G01X281420Y637250D02*
X278150D01*
G01X222500Y630200D02*
X221900Y629600D01*
Y627150D01*
G01X247088Y610236D02*
Y612538D01*
X247900Y613350D01*
G01X278150Y637250D02*
Y640772D01*
G01X284945Y576463D02*
X280957D01*
X279450Y577970D01*
G01X246500Y602500D02*
X246000Y602000D01*
X244350D01*
X243350Y601000D01*
G01X261900Y588900D02*
X261221Y589579D01*
X258508D01*
G01X251150Y585700D02*
X253625D01*
X254408Y586483D01*
G01X255400Y579500D02*
X254200Y578300D01*
X252150D01*
G01X225900Y630700D02*
X226720Y629880D01*
X229952D01*
G01X225900Y630700D02*
Y627150D01*
G01Y630988D02*
Y630700D01*
G01X279745Y612019D02*
Y608000D01*
G01X251900Y616850D02*
X254750D01*
X255663Y617763D01*
G01X250924Y623114D02*
X253186D01*
X255663Y620637D01*
Y617763D01*
G01X232650Y634300D02*
X231300D01*
X229952Y632952D01*
Y629880D01*
G01X252050Y573500D02*
X252150Y573600D01*
Y578300D01*
G01X300043Y603619D02*
X294900Y608762D01*
Y620244D01*
X282344Y632800D01*
X275950D01*
X269250Y639500D01*
G01X246975Y633776D02*
Y631765D01*
X244824Y629614D01*
G01X238700Y617900D02*
X239600Y618800D01*
X241000D01*
X243324Y621124D01*
Y623114D01*
G01X235800Y615100D02*
X235900D01*
X238700Y617900D01*
G01X244824Y629614D02*
X243324Y628114D01*
Y623114D01*
G01X267500Y645600D02*
Y648902D01*
X268456Y649858D01*
G01X252250Y656375D02*
X247725D01*
G01X263000Y675750D02*
X266550D01*
G01X252250Y670375D02*
X247825D01*
G01X230315Y679921D02*
X235100D01*
G01X232000Y642650D02*
Y644203D01*
X230270Y645933D01*
G01X228200Y642650D02*
X232000D01*
G01X262645Y708285D02*
Y712155D01*
G01X282600Y685650D02*
X281850Y686400D01*
X279400D01*
G01X269003Y704337D02*
X272253D01*
G01X282620Y644150D02*
Y640950D01*
G01X258000Y657250D02*
X255727D01*
X254852Y656375D01*
X252250D01*
G01X263050Y666000D02*
Y662498D01*
X262826Y662274D01*
G01X263026Y669731D02*
Y666024D01*
X263050Y666000D01*
G01X223400Y641450D02*
Y645285D01*
X223013Y645672D01*
G01X263800Y648902D02*
X263702Y649000D01*
X261959D01*
X259173Y646214D01*
X258000D01*
G01X225984Y658993D02*
X226010Y658967D01*
X231367D01*
X231500Y659100D01*
G01X235439Y662667D02*
Y661814D01*
X232725Y659100D01*
X231500D01*
G01X255050Y675750D02*
X258500D01*
G01X250800Y675850D02*
X254950D01*
X255050Y675750D01*
G01X258431Y708274D02*
Y712169D01*
G01X243731Y705824D02*
Y709100D01*
G01X271200Y672650D02*
Y670800D01*
X272900Y669100D01*
G01X278150Y644572D02*
Y648363D01*
G01D02*
X279944D01*
X280329Y647978D01*
X282620D01*
G01X284000Y678300D02*
Y679800D01*
X282600Y681200D01*
Y682150D01*
G01X236000Y642650D02*
Y646100D01*
G01X263000Y679250D02*
X266398D01*
G01X262645Y704785D02*
X258442D01*
X258431Y704774D01*
G01X283032Y736436D02*
Y739341D01*
X282353Y740020D01*
G01X272070Y715620D02*
X271550Y715100D01*
X268820D01*
G01X271970Y719420D02*
X268520D01*
G01X345034Y128612D02*
X340706D01*
G01X345034Y112112D02*
Y108568D01*
X345069Y108533D01*
G01X340034Y112112D02*
Y108478D01*
X340080Y108432D01*
G01X353987Y104200D02*
X357500D01*
G01X346457Y81065D02*
Y84567D01*
G01D02*
Y88069D01*
G01X342955Y84567D02*
X346457D01*
G01D02*
X349959D01*
G01X297146Y205315D02*
X305665D01*
X306407Y206057D01*
G01X314666Y205315D02*
X307149D01*
X306407Y206057D01*
G01X314666Y208465D02*
X308815D01*
X306407Y206057D01*
G01X297146Y202165D02*
X303117D01*
X303648Y202696D01*
X305703D01*
G01X343582Y181928D02*
X341872D01*
X338872Y184928D01*
X334782D01*
G01X330563Y208041D02*
Y189147D01*
X334782Y184928D01*
G01X347600Y186900D02*
X350100Y184400D01*
X356908D01*
X357682Y185174D01*
G01X297146Y262008D02*
X303548D01*
X304548Y261008D01*
G01X297146Y258858D02*
X302398D01*
X304548Y261008D01*
G01X314666Y252559D02*
X319323D01*
X321197Y254433D01*
G01X314666Y255709D02*
X319921D01*
X321197Y254433D01*
G01X314666Y268307D02*
X319460D01*
X321281Y266486D01*
G01X297146Y274606D02*
X302450D01*
X304548Y272508D01*
G01X297146Y271457D02*
X303497D01*
X304548Y272508D01*
G01X314666Y265158D02*
X319953D01*
X321281Y266486D01*
G01X314666Y277756D02*
X320098D01*
X321432Y279090D01*
G01X314666Y280906D02*
X319616D01*
X321432Y279090D01*
G01X297146Y230512D02*
X302144D01*
X305182Y227474D01*
X305382D01*
G01X335100Y228117D02*
X335200Y228017D01*
X340298D01*
G01X297146Y208465D02*
X304313D01*
X305862Y210014D01*
G01X331500Y208978D02*
X330563Y208041D01*
G01X297146Y337599D02*
X303260D01*
X304267Y336592D01*
G01X297146Y334449D02*
X302124D01*
X304267Y336592D01*
G01X297146Y312402D02*
X303257D01*
X304267Y311392D01*
G01X297146Y309252D02*
X302127D01*
X304267Y311392D01*
G01X297146Y287205D02*
X303254D01*
X304267Y286192D01*
G01X297146Y284055D02*
X302130D01*
X304267Y286192D01*
G01X297146Y325000D02*
X302159D01*
X304267Y322892D01*
G01X314666Y290354D02*
X320362D01*
X321882Y291874D01*
G01X314666Y293504D02*
X320252D01*
X321882Y291874D01*
G01X314666Y302953D02*
X320461D01*
X321882Y304374D01*
G01X314666Y306102D02*
X314667Y306103D01*
X320153D01*
X321882Y304374D01*
G01X314666Y315551D02*
X320098D01*
X321432Y316885D01*
G01X314666Y318701D02*
X319616D01*
X321432Y316885D01*
G01X314666Y328150D02*
X320098D01*
X321432Y329484D01*
G01X314666Y331299D02*
X319617D01*
X321432Y329484D01*
G01X314666Y340748D02*
X320098D01*
X321432Y342082D01*
G01X314666Y343898D02*
X319616D01*
X321432Y342082D01*
G01X297146Y296654D02*
X303229D01*
X304267Y297692D01*
G01X297146Y299803D02*
X302156D01*
X304267Y297692D01*
G01X297146Y321850D02*
X303225D01*
X304267Y322892D01*
G01X297146Y347047D02*
X303222D01*
X304267Y348092D01*
G01X297146Y350197D02*
X302162D01*
X304267Y348092D01*
G01X297146Y362795D02*
X303264D01*
X304267Y361792D01*
G01X297146Y359646D02*
X302121D01*
X304267Y361792D01*
G01X314666Y365945D02*
X319298D01*
X320832Y367479D01*
G01X314666Y353347D02*
X320098D01*
X321432Y354681D01*
G01X314666Y356496D02*
X319617D01*
X321432Y354681D01*
G01X314666Y369095D02*
X319216D01*
X320832Y367479D01*
G01X297146Y372244D02*
X303219D01*
X304267Y373292D01*
G01X297146Y375394D02*
X302165D01*
X304267Y373292D01*
G01X363942Y450591D02*
Y452558D01*
X347650Y468850D01*
Y490331D01*
X348997Y491678D01*
G01X350879Y520400D02*
X351379Y520900D01*
X353800D01*
X355781Y522881D01*
X359088D01*
G01X293645Y539294D02*
Y541028D01*
X292200Y542473D01*
G01X347750Y511900D02*
X344700D01*
X344600Y511800D01*
G01X319550Y526100D02*
Y524250D01*
X318200Y522900D01*
G01X346819Y520625D02*
X350654D01*
X350879Y520400D01*
G01X350400Y528450D02*
X347390D01*
X346440Y527500D01*
G01X342497Y520611D02*
X339551D01*
X339062Y521100D01*
G01X334827Y520603D02*
X338565D01*
X339062Y521100D01*
G01X347811Y507831D02*
X344831D01*
X344600Y507600D01*
G01X341300Y536200D02*
X345050D01*
X345100Y536150D01*
G01X341226Y531959D02*
Y536126D01*
X341300Y536200D01*
G01X287050Y522800D02*
X288390D01*
X290889Y525299D01*
G01D02*
X292024Y526434D01*
G01X306503Y620550D02*
Y622701D01*
X305470Y623734D01*
G01X294167Y585868D02*
X297767D01*
G01X331750Y585000D02*
Y581394D01*
G01D02*
X333195Y579949D01*
X334923D01*
G01X317600Y606850D02*
Y603302D01*
X317572Y603274D01*
Y603183D01*
G01X318750Y599000D02*
Y602005D01*
X317572Y603183D01*
G01X294167Y585868D02*
X292032D01*
X290900Y587000D01*
X287600D01*
G01X299100Y589200D02*
X297767Y587867D01*
Y585868D01*
G01X304617Y589831D02*
X305849D01*
X307542Y588138D01*
G01X294167Y582368D02*
X297767D01*
G01X302300Y582000D02*
X298135D01*
X297767Y582368D01*
G01X286700Y611911D02*
Y614958D01*
X286703Y614961D01*
G01X352472Y581000D02*
X347750D01*
G01X352472D02*
Y584106D01*
X352480Y584114D01*
G01X356680Y585614D02*
X355180Y584114D01*
X352480D01*
G01X325762Y596900D02*
X323662Y599000D01*
X322250D01*
G01X328250Y585000D02*
X326882D01*
X324900Y583018D01*
Y581600D01*
G01D02*
X328044D01*
X328250Y581394D01*
G01X296265Y592831D02*
X292918D01*
X292087Y592000D01*
X287600D01*
G01X296265Y592831D02*
Y591324D01*
X294507Y589566D01*
X293697D01*
G01X288445Y576463D02*
Y573705D01*
X289070Y573080D01*
G01X294832Y691947D02*
X294804Y691975D01*
Y695204D01*
G01X360049Y651827D02*
X355100D01*
G01X328374Y691970D02*
X332800D01*
G01X351547Y645938D02*
Y648274D01*
X355100Y651827D01*
G01X374200Y645871D02*
Y655165D01*
X371981Y657384D01*
X355066D01*
X353651Y655969D01*
Y653235D01*
X355059Y651827D01*
X355100D01*
G01X352180Y642214D02*
Y645305D01*
X351547Y645938D01*
G01X318000Y678270D02*
X314720D01*
G01X339350Y658625D02*
Y661550D01*
X340000Y662200D01*
G01X314398Y670254D02*
Y668742D01*
X317136Y666004D01*
G01X318000Y678270D02*
X318173Y678443D01*
X321425D01*
G01X328374Y684270D02*
X332824D01*
G01X347680Y639714D02*
X348314Y640348D01*
Y643853D01*
G01X332824Y684270D02*
X333830Y685276D01*
X336631D01*
G01X339350Y658625D02*
X332750D01*
X332475Y658350D01*
G01X294018Y665782D02*
Y667218D01*
X295682Y668882D01*
X297118D01*
G01X304100Y666500D02*
X304596Y666004D01*
X309236D01*
G01X303100Y661630D02*
Y664200D01*
X304100Y665200D01*
Y666500D01*
G01X328356Y678679D02*
X329627Y679950D01*
X331928D01*
X332654Y680676D01*
X335531D01*
X336631Y681776D01*
G01D02*
X339324D01*
X342150Y678950D01*
Y672000D01*
G01X299000Y661550D02*
Y663700D01*
X297900Y664800D01*
G01X289612Y664979D02*
Y667212D01*
X290600Y668200D01*
G01X338173Y677472D02*
Y674035D01*
X338301Y673907D01*
G01X306370Y738774D02*
Y742200D01*
X306470D01*
Y743570D01*
G01X298470Y738774D02*
Y741900D01*
X298570D01*
Y743670D01*
G01X291700Y733650D02*
Y737000D01*
G01X287620Y733670D02*
Y737520D01*
X287220Y737920D01*
G01X376020Y48200D02*
X382631D01*
G01X376020Y52800D02*
X382547D01*
G01X369400Y115950D02*
X363400D01*
G01X375720Y86300D02*
X380800D01*
X382500Y88000D01*
G01X370650Y193564D02*
X370800Y193714D01*
Y197045D01*
X370554Y197291D01*
G01X365900Y198500D02*
X366400Y199000D01*
X368845D01*
X370554Y197291D01*
G01X360382Y193650D02*
X360832Y193200D01*
X365250D01*
X365800Y193750D01*
G01X364000Y240100D02*
X366057D01*
X367230Y241273D01*
Y241308D01*
G01Y245508D02*
X365392D01*
X363828Y243944D01*
G01X364600Y491950D02*
X361550D01*
X361250Y491650D01*
G01X359481Y487916D02*
Y489881D01*
X361250Y491650D01*
G01X389850Y564400D02*
X393100D01*
G01X387800Y529400D02*
X389250Y530850D01*
Y533400D01*
G01X389050Y541100D02*
X389250Y540900D01*
Y533400D01*
G01X387400Y547500D02*
Y544200D01*
X385550Y542350D01*
Y541100D01*
G01D02*
X381300D01*
X379088Y538888D01*
Y537881D01*
G01X384300Y551850D02*
X384935Y552485D01*
X388489D01*
G01D02*
Y548989D01*
X387400Y547900D01*
Y547500D01*
G01X394800Y609700D02*
Y611700D01*
X392600Y613900D01*
X391250D01*
G01X361120Y585636D02*
Y582726D01*
X360980Y582586D01*
G01X370220Y580586D02*
Y579582D01*
X372951Y576851D01*
G01X393050Y597200D02*
X396200D01*
G01X369273Y645871D02*
X374200D01*
G01X386050Y698000D02*
Y701200D01*
G01X382550Y698000D02*
Y705043D01*
X383900Y706393D01*
Y711500D01*
X383600Y711800D01*
G01X379450Y710400D02*
Y714400D01*
G01X375950Y710400D02*
X373400D01*
X372100Y711700D01*
G01X470531Y-23804D02*
Y-103804D01*
G01X486535Y47449D02*
X486856D01*
X486864Y47457D01*
X490035D01*
G01X485764Y51841D02*
X482732D01*
X482397Y52176D01*
G01X482976Y55778D02*
Y52755D01*
X482397Y52176D01*
G01X446788Y55180D02*
X449630D01*
X450288Y54522D01*
G01X460300Y57600D02*
X462304D01*
X462596Y57308D01*
X464342D01*
G01X503854Y42093D02*
Y45153D01*
X505633Y46932D01*
G01X608031Y-23804D02*
Y-103804D01*
G01X579297Y37207D02*
X576919Y39585D01*
X576649D01*
G01X579104Y45967D02*
X575300D01*
G01X622364Y24999D02*
X622537Y25172D01*
Y30976D01*
G01X622364Y24999D02*
X621336Y23971D01*
X616857D01*
G01X618546Y50576D02*
Y55138D01*
G01X626700Y60200D02*
X629711Y63211D01*
X631781D01*
G01X626700Y60200D02*
Y59792D01*
X622046Y55138D01*
G01X603747Y67907D02*
Y71407D01*
G01X710550Y23025D02*
Y18550D01*
G01X704150Y423800D02*
X700900D01*
G01X712851Y474832D02*
Y470205D01*
X712874Y470182D01*
G01X707650Y423800D02*
X711300D01*
G01X712000Y438850D02*
Y442100D01*
G01X671785Y479785D02*
Y476573D01*
G01D02*
X669749Y474537D01*
Y458022D01*
G01X653833Y530195D02*
X657199D01*
G01X653628Y517560D02*
X650346Y520842D01*
Y521633D01*
X650296Y521683D01*
G01X653634Y513757D02*
Y517554D01*
X653628Y517560D01*
G01X723031Y-23804D02*
Y-103804D01*
G01X723800Y21950D02*
Y18600D01*
G01X787050Y422800D02*
X783800D01*
G01X716100Y438850D02*
Y442100D01*
G01X721100Y438850D02*
Y442100D01*
G01X737250Y426800D02*
X740500D01*
G01X725200Y438850D02*
Y442100D01*
G01X737250Y431000D02*
X740500D01*
G01X720017Y475164D02*
X723800D01*
G01X754800Y530450D02*
Y534000D01*
X753800Y535000D01*
G01X854596Y159085D02*
Y155288D01*
G01X840122Y160314D02*
Y156614D01*
G01X846561Y169478D02*
X846550Y169467D01*
X843160D01*
G01X846561Y165178D02*
X843611D01*
X842511Y164078D01*
G01X858632Y216929D02*
X859604Y215957D01*
Y214067D01*
X860968Y212703D01*
Y210564D01*
G01X850730Y354028D02*
Y350483D01*
G01X839666Y351914D02*
Y350364D01*
X841116Y348914D01*
G01X857320Y405672D02*
Y408772D01*
X856720Y409372D01*
G01X845820Y366572D02*
Y366979D01*
X847720Y368879D01*
Y371072D01*
G01X820150Y425800D02*
Y421050D01*
X822300Y418900D01*
G01X830531Y361589D02*
X831809Y360311D01*
X836163D01*
G01X804000Y437850D02*
Y441100D01*
G01X799000Y437850D02*
Y441100D01*
G01X811099Y473729D02*
Y470401D01*
X811142Y470358D01*
G01X820150Y430000D02*
Y433900D01*
G01X790550Y422800D02*
X794200D01*
G01X808100Y437850D02*
Y441100D01*
G01X794900Y437850D02*
Y441100D01*
G01X823710Y469835D02*
X823728Y469853D01*
Y473550D01*
G01X890531Y-23804D02*
Y-103804D01*
G01X894784Y192800D02*
Y187132D01*
X894711Y187059D01*
G01X893974Y182685D02*
Y186322D01*
X894711Y187059D01*
G01X891166Y381316D02*
Y375486D01*
X890963Y375283D01*
G01X890639Y371110D02*
Y374959D01*
X890963Y375283D01*
G01X861420Y367269D02*
X862177Y368026D01*
Y368262D01*
G01X1060531Y-23804D02*
Y-103804D01*
G01X1258031Y-23804D02*
Y-103804D01*
G01X1286031Y-7804D02*
G02I-12000J0D01*
G01X1280881D02*
G02I-6850J0D01*
G01X1274031Y-23804D02*
Y8196D01*
G01X1290031Y-7804D02*
X1258031D01*
X43000Y59500D03*
X51000D03*
X34000Y59400D03*
X38500Y56500D03*
X46500Y48500D03*
X28123Y453658D03*
X62276Y550493D03*
X37660Y566400D03*
X64427Y538836D03*
X67853Y558117D03*
X64701Y564416D03*
X28782Y555119D03*
X34132Y521245D03*
X34175Y526969D03*
X29165Y532612D03*
X29058Y538228D03*
X29158Y543855D03*
X28800Y549474D03*
X33697Y560866D03*
X61100Y546700D03*
X64277Y502177D03*
X67852Y539219D03*
X67853Y564416D03*
Y554967D03*
Y542368D03*
X64701Y561266D03*
X63456Y555041D03*
X67853Y561266D03*
X64701Y542366D03*
X64151Y521695D03*
X53524Y521269D03*
Y526995D03*
Y532622D03*
X52613Y538242D03*
X52408Y543876D03*
X52603Y549526D03*
X52485Y555153D03*
X53300Y560879D03*
X42597Y571789D03*
X67852Y583313D03*
X67853Y573865D03*
X67852Y586463D03*
X64701Y570716D03*
X67853Y577015D03*
X64703Y586463D03*
X64701Y567566D03*
X67853Y570715D03*
X53302Y567317D03*
X58926Y582407D03*
X28667Y634097D03*
X42550Y599224D03*
X50400Y663700D03*
X50500Y667900D03*
X64884Y650984D03*
X37961Y659909D03*
X41100Y671800D03*
X56100Y676000D03*
X86268Y58755D03*
X90768Y69755D03*
X82768D03*
X73768Y69655D03*
X78268Y66755D03*
X121233Y450900D03*
X104000Y475500D03*
X118197Y490300D03*
X108500Y475500D03*
X97074Y492891D03*
X112722Y493971D03*
X98400Y473200D03*
X140490Y488605D03*
X132777Y462639D03*
X130787Y479138D03*
X113300Y448564D03*
X118065Y448535D03*
X100600Y490750D03*
X138023Y456188D03*
X140985Y454250D03*
X135262Y475726D03*
X105350Y511850D03*
X89899Y564415D03*
X119400Y511500D03*
X135012Y510200D03*
X94473Y547093D03*
X106272Y547370D03*
X89899Y558115D03*
X138900Y525999D03*
X136974Y534479D03*
X120500Y504600D03*
X69904Y502077D03*
X75399Y502179D03*
X81094Y502166D03*
X86699Y502300D03*
X97926D03*
X74151Y545516D03*
X86750Y542368D03*
X126337Y554085D03*
X74498Y551757D03*
X130311Y546700D03*
X71002Y539219D03*
X81276Y548766D03*
X119605Y548705D03*
X86750Y539218D03*
X74076Y535966D03*
X83600Y545518D03*
X75508Y542198D03*
X89899Y545518D03*
X127300Y543200D03*
X71002Y542368D03*
X117200Y546300D03*
X89899Y539218D03*
X83600Y539219D03*
X71002Y545518D03*
X86750D03*
X122600Y557480D03*
X71002Y558117D03*
X86750Y554965D03*
Y558115D03*
X83600Y551817D03*
X71002Y564396D03*
Y561266D03*
X83600Y564415D03*
X86750D03*
X75066Y563235D03*
X83600Y561265D03*
X71002Y554967D03*
X86750Y551815D03*
X123300Y530300D03*
X119400Y521700D03*
X133800Y528500D03*
X102601Y507300D03*
X123200Y534600D03*
X78276Y545566D03*
X93744Y542019D03*
X133554Y537374D03*
X71002Y548668D03*
X92600Y535623D03*
X86750Y561265D03*
X89899D03*
X94720Y557158D03*
X92286Y521695D03*
X86659D03*
X81032D03*
X75405D03*
X69778D03*
X97913D03*
X96371Y534124D03*
X125400Y498600D03*
X140400Y607850D03*
X137000D03*
X130700D03*
X135706Y621187D03*
X119900Y621000D03*
X131200Y620600D03*
X108371Y577258D03*
X86750Y567565D03*
X89901Y587466D03*
X93048Y577014D03*
X86750Y573864D03*
X89899D03*
X71002Y577013D03*
X85400Y629784D03*
X75197Y572437D03*
X130607Y569636D03*
X126347Y569556D03*
X117400Y567650D03*
X83600Y573865D03*
X74152Y567565D03*
X86750Y586463D03*
X71002Y567565D03*
X86750Y583313D03*
X74152Y580163D03*
X83601Y580164D03*
X89899Y577014D03*
X74152Y577013D03*
X86750Y577014D03*
X96570Y581730D03*
X118900Y609900D03*
X116400Y626600D03*
X124903Y613900D03*
X124793Y617299D03*
X139500Y611200D03*
X138970Y632277D03*
X74152Y583312D03*
X94011Y597066D03*
X101608Y596523D03*
X93048Y580164D03*
X89899Y567565D03*
X93049Y573864D03*
X93051Y587466D03*
X83600Y567565D03*
X128700Y615500D03*
X138700Y636655D03*
X103098Y620264D03*
X98537Y601094D03*
X102509Y601100D03*
X103109Y608572D03*
X103124Y605153D03*
X103098Y612064D03*
Y624364D03*
X113672Y605134D03*
X113512Y613401D03*
X113426Y609234D03*
X108137Y615870D03*
X113400Y621400D03*
Y617400D03*
X70700Y629000D03*
X133835Y609620D03*
X127100Y647000D03*
X123100D03*
X119000D03*
X73427Y699285D03*
X104550Y647050D03*
X104850Y639150D03*
X111300Y705500D03*
X86028Y696439D03*
X81928Y697539D03*
X106879Y707245D03*
X125376Y701124D03*
X106635Y701465D03*
X94106Y699683D03*
X131300Y650100D03*
X135000Y650000D03*
X89868Y689124D03*
X121300Y651900D03*
X139774Y666686D03*
X119849Y709715D03*
X106355Y710745D03*
X148000Y469000D03*
X196100Y482200D03*
X170870Y492270D03*
X186254Y463761D03*
X143700Y469000D03*
X188708Y468154D03*
X175115Y463761D03*
X167821Y488301D03*
X208370Y491570D03*
X200260Y465900D03*
X211324Y489886D03*
X167656Y465300D03*
X189700Y463500D03*
X181200Y489451D03*
X155710Y485200D03*
X172300Y478400D03*
X172900Y484101D03*
X169252Y483871D03*
X213159Y460326D03*
X154334Y465100D03*
X149000Y488600D03*
X171537Y464400D03*
X179100Y455800D03*
X201600Y486500D03*
X198200D03*
X190036Y485520D03*
X194411Y485447D03*
X163031Y441700D03*
X193400Y463300D03*
X153489Y481559D03*
X148490Y451286D03*
X144245Y452344D03*
X151877Y450439D03*
X155877D03*
X145000Y488600D03*
X167680Y510640D03*
X166761Y498900D03*
X198700Y513500D03*
X203350Y506700D03*
X188600Y531500D03*
X179000Y499800D03*
X203500Y513500D03*
X191398Y509000D03*
X211700Y513500D03*
X208700Y529100D03*
X207500Y502412D03*
X145000Y497600D03*
X187500Y523700D03*
X154730Y512704D03*
X158241Y512675D03*
X170700Y513600D03*
X182870Y513832D03*
X212300Y529000D03*
X141980Y508590D03*
X146900Y512500D03*
X185615Y498015D03*
X174900Y499800D03*
X203610Y529397D03*
X179400Y525100D03*
X182964Y510414D03*
X154400Y533500D03*
X187100Y509600D03*
X195200Y513200D03*
X162537Y499000D03*
X160286Y508429D03*
X183750Y524200D03*
X143415Y530143D03*
X171200Y509840D03*
X170800Y499800D03*
X166600Y524100D03*
X144087Y526413D03*
X176900Y496500D03*
X174717Y524010D03*
X178869Y509793D03*
X200650Y497862D03*
X199501Y509275D03*
X191200Y522500D03*
X191300Y525900D03*
X174700Y509600D03*
X207500Y505812D03*
X158000Y499000D03*
X200200Y529200D03*
X156000Y496100D03*
X203696Y533000D03*
X156200Y535800D03*
X188834Y496920D03*
X190929Y512592D03*
X150553Y512500D03*
X148050Y523740D03*
X196800Y497862D03*
X193200Y497000D03*
X174400Y519283D03*
X200963Y636600D03*
X212923Y615000D03*
X191210Y617900D03*
X203300Y628900D03*
X148409Y575672D03*
X144876Y590854D03*
X148409Y579353D03*
X144876Y587173D03*
X185100Y614300D03*
X179700Y615300D03*
X151800Y615400D03*
X197611Y630698D03*
X193400Y630600D03*
X174799Y630303D03*
X171400Y630200D03*
X199950Y614000D03*
X196100Y614050D03*
X203900Y614100D03*
X144737Y630882D03*
X200100Y633300D03*
X209193Y614249D03*
X162750Y612217D03*
X164400Y609200D03*
X182100Y629800D03*
X178200D03*
X148210Y629830D03*
X141742Y624666D03*
X144263Y609023D03*
X151800Y610300D03*
X188899Y629597D03*
X185500Y629700D03*
X154500Y629600D03*
X195600Y646000D03*
X166500Y640300D03*
X191766Y679920D03*
X211706Y645349D03*
X208200Y645500D03*
X148249Y695765D03*
X151130Y703440D03*
X184807Y643963D03*
X188500Y686800D03*
X205827Y695000D03*
X188600Y696800D03*
X159058Y641132D03*
X142572Y640332D03*
X150872D03*
X177100Y640400D03*
X173000D03*
X193400Y639700D03*
X189500D03*
X185300D03*
X181000D03*
X198700D03*
X151949Y691715D03*
X176447Y704925D03*
X162700Y703500D03*
X150849Y710215D03*
X162360Y706888D03*
X168273Y696434D03*
X158994Y694545D03*
X205800Y698400D03*
X210123Y662100D03*
X200000Y664200D03*
X204100Y646500D03*
X199600Y646300D03*
X195500Y696900D03*
X207000Y654400D03*
X185598Y709274D03*
X182200Y709400D03*
X143174Y666586D03*
X162100Y711215D03*
X275276Y494017D03*
X213900Y474650D03*
X227100Y490300D03*
X275300Y467300D03*
X275700Y490300D03*
X275100Y472400D03*
X264800Y467400D03*
X278800Y467500D03*
X277455Y446150D03*
X226475Y480400D03*
X254100Y440800D03*
X257950Y440600D03*
X226500Y477000D03*
X275113Y476513D03*
X266664Y493000D03*
X214808Y463300D03*
X231400Y489800D03*
X237903D03*
X267670Y485870D03*
X271100Y485900D03*
X222995Y443805D03*
X240900Y440900D03*
X236400Y440800D03*
X280600Y448900D03*
X214900Y490000D03*
X231476Y449662D03*
X276591Y483709D03*
X245874Y458478D03*
X242500Y458900D03*
X253400Y453500D03*
X273400Y449700D03*
X249465Y458000D03*
X252626Y469150D03*
X244400Y478600D03*
X244300Y474150D03*
X225532Y450047D03*
X237600Y455500D03*
X233664Y482859D03*
X226607Y444058D03*
X230610Y444055D03*
X234648Y540453D03*
X221960Y504230D03*
X222500Y536161D03*
X279600Y527900D03*
X272100Y537500D03*
X251346Y554100D03*
X256816Y563982D03*
X262996Y548757D03*
X231450Y563000D03*
X270021Y549394D03*
X283600Y539294D03*
X242700Y548600D03*
X252400Y539600D03*
X271715Y556690D03*
X263400Y531500D03*
X233850Y552201D03*
X234943Y565199D03*
X265100Y562300D03*
X227600Y563000D03*
X254494Y529198D03*
X248459Y523892D03*
X269100Y509063D03*
X244850Y540150D03*
X248700Y540000D03*
X228200Y496200D03*
X263600Y540700D03*
X226357Y504514D03*
X257894Y529254D03*
X263600Y535350D03*
X223800Y531600D03*
X236400Y502150D03*
X246508Y532821D03*
X228100Y545500D03*
X227100Y525400D03*
X228800Y542100D03*
X238600Y509900D03*
X228313Y552169D03*
X233100Y509800D03*
X275100D03*
X260900Y553900D03*
X242600Y509800D03*
X233607Y557671D03*
X241154Y536017D03*
X250445Y548551D03*
X255800Y539600D03*
X279200Y531600D03*
X250400Y636976D03*
X215800Y631200D03*
X260705Y598359D03*
X232896Y613795D03*
X279450Y577970D03*
X260850Y603537D03*
X274800Y607500D03*
X258600Y613100D03*
X254208Y603995D03*
X254043Y598359D03*
X247088Y610236D03*
X254821Y627000D03*
X255228Y631071D03*
X278150Y637250D03*
X229800Y593200D03*
X246800Y589600D03*
X261900Y588900D03*
X245400Y581800D03*
X264358Y608152D03*
X241300Y635900D03*
X228900Y635800D03*
X222500Y630200D03*
X218800Y635600D03*
X225900Y615000D03*
X221800Y614800D03*
X246500Y602500D03*
X234000Y628400D03*
X230900Y581600D03*
X270300Y622315D03*
X281500Y598419D03*
X231200Y576800D03*
X234700Y581600D03*
X254408Y586483D03*
X255400Y579500D03*
X225900Y630988D03*
X230063Y618667D03*
X274100Y591000D03*
X279745Y608000D03*
X255663Y617763D03*
X276376Y574132D03*
X281636Y588796D03*
X231000Y571900D03*
X242333Y593800D03*
X257346Y599169D03*
X257332Y602569D03*
X258398Y605915D03*
Y609484D03*
X218200Y609500D03*
X262694Y568076D03*
X261300Y571300D03*
X235800Y615100D03*
X233447Y603747D03*
X232300Y600300D03*
X258596Y586356D03*
X259848Y583194D03*
X279214Y591383D03*
X275652Y577455D03*
X237100Y590000D03*
X234087Y618038D03*
X248800Y582000D03*
X273022Y580751D03*
X268200Y578700D03*
X259000Y617000D03*
X234800Y572000D03*
X256007Y575050D03*
X281975Y572963D03*
X279800Y569182D03*
X264200Y574100D03*
X261810Y633980D03*
X264800Y632300D03*
X276783Y588907D03*
X258873Y631373D03*
X215400Y626800D03*
X281510Y583003D03*
X276400Y700650D03*
X254900Y701950D03*
X267500Y645600D03*
X280500Y708100D03*
X269003Y704337D03*
X282620Y640950D03*
X262826Y662274D03*
X245100Y639500D03*
X219200Y645300D03*
X230270Y645933D03*
X247725Y656375D03*
X261900Y699300D03*
X266550Y675750D03*
X247825Y670375D03*
X245971Y698400D03*
X235100Y679921D03*
X221575Y695400D03*
X279400Y686400D03*
X223013Y645672D03*
X231500Y659100D03*
X255050Y675750D03*
X271240Y698960D03*
X243731Y709100D03*
X272900Y669100D03*
X254600Y685100D03*
X278150Y648363D03*
X284000Y678300D03*
X263800Y648902D03*
X236000Y646100D03*
X272300Y665700D03*
X266398Y679250D03*
X226708Y645869D03*
X239400Y677600D03*
X267045Y695881D03*
X215606Y645300D03*
X277600Y680200D03*
X217638Y695562D03*
X239000Y691000D03*
X276400Y697250D03*
X254700Y708900D03*
X271220Y679910D03*
X255000Y679900D03*
X235042Y656173D03*
X263500Y643212D03*
X243100Y677500D03*
X267100Y699700D03*
X266400Y662200D03*
X280600Y711700D03*
X282353Y740020D03*
X268820Y715100D03*
X262645Y712155D03*
X254648Y745463D03*
X268520Y719420D03*
X258431Y712169D03*
X268230Y723570D03*
X345069Y108533D03*
X340080Y108432D03*
X348900Y115400D03*
X340706Y128612D03*
X352000Y109000D03*
X355500D03*
X305703Y202696D03*
X306407Y206057D03*
X355300Y179300D03*
X354282Y187718D03*
Y191718D03*
X305651Y199283D03*
X294720Y182200D03*
X320700Y177800D03*
X294720Y178600D03*
Y185600D03*
X307567Y277592D03*
Y273592D03*
X304548Y272508D03*
Y268508D03*
Y265008D03*
Y261008D03*
X321432Y279090D03*
X321281Y266486D03*
X321197Y254433D03*
X306446Y247874D03*
X323842Y219284D03*
X305498Y213824D03*
X305382Y227474D03*
X323800Y227000D03*
X323700Y230600D03*
X335100Y228117D03*
X333882Y273978D03*
Y270578D03*
X335098Y233078D03*
X305782Y230874D03*
X334482Y263778D03*
X333782Y267178D03*
X324000Y222800D03*
X305782Y220674D03*
X305682Y224074D03*
X305782Y217274D03*
X334198Y248824D03*
X305454Y244461D03*
X334282Y252378D03*
X305373Y251101D03*
X306412Y254339D03*
X334260Y255820D03*
X305882Y234274D03*
X305772Y237673D03*
X305781Y241076D03*
X334107Y291354D03*
Y287354D03*
Y283854D03*
Y279854D03*
X307567Y349192D03*
X304267Y348092D03*
Y344092D03*
Y340592D03*
Y336592D03*
X307567Y335492D03*
Y331492D03*
Y327992D03*
Y323992D03*
X304267Y322892D03*
Y318892D03*
Y315392D03*
Y311392D03*
X307567Y310292D03*
Y306292D03*
Y302792D03*
Y298792D03*
X304267Y297692D03*
Y293692D03*
Y290192D03*
Y286192D03*
X334582Y341721D03*
Y337721D03*
Y334221D03*
Y330221D03*
X328187Y350316D03*
Y346816D03*
Y342816D03*
X328182Y329124D03*
Y325124D03*
Y321624D03*
Y317624D03*
X334593Y316584D03*
Y312584D03*
Y309084D03*
Y305084D03*
X328182Y303977D03*
Y299977D03*
Y296477D03*
Y292477D03*
X307567Y285092D03*
Y281092D03*
X321432Y342082D03*
Y329484D03*
Y316885D03*
X321882Y304374D03*
Y291874D03*
X304267Y373292D03*
Y369292D03*
Y365792D03*
Y361792D03*
X307567Y360692D03*
Y356692D03*
Y353192D03*
X328182Y379518D03*
Y375518D03*
Y372018D03*
Y368018D03*
X334582Y366974D03*
Y362974D03*
Y359474D03*
Y355474D03*
X328187Y354316D03*
X320832Y367479D03*
X321432Y354681D03*
X320932Y377074D03*
X340606Y389899D03*
X336000Y384400D03*
X336230Y377800D03*
X350408Y393708D03*
X348006Y391300D03*
X321859Y388315D03*
X321100Y384874D03*
X346300Y374600D03*
X349100Y379100D03*
X303900Y380574D03*
X348997Y491678D03*
X295700Y428400D03*
X293326Y494174D03*
X344900Y442800D03*
X344688Y493896D03*
X343050Y438900D03*
X339900Y454000D03*
X328313Y435513D03*
X324916Y435360D03*
X321700Y436650D03*
X296254Y546706D03*
X305350Y514300D03*
X292200Y542473D03*
X285800Y549394D03*
X346440Y527500D03*
X350879Y520400D03*
X352734Y541826D03*
X355700Y510000D03*
X344600Y511800D03*
X326900Y507700D03*
X304800Y554443D03*
X318200Y522900D03*
X285833Y557629D03*
X302700Y551300D03*
X339062Y521100D03*
X344600Y507600D03*
X341300Y536200D03*
X352921Y536521D03*
X311900Y514900D03*
X287500Y518000D03*
X297850Y524500D03*
X293600Y518400D03*
X288000Y561000D03*
X313300Y518800D03*
X354300Y500245D03*
X288311Y496200D03*
X355600Y506600D03*
X298200Y521100D03*
X301300Y524400D03*
X355600Y513500D03*
X327300Y540100D03*
X341400Y560050D03*
X336881Y530496D03*
X307800Y546700D03*
X341615Y556015D03*
X336953Y534506D03*
X305913Y549643D03*
X331900Y549700D03*
X329050Y552315D03*
X348220Y563836D03*
X344812Y563844D03*
X344755Y497841D03*
X304436Y564081D03*
X341349Y563750D03*
X307350Y561290D03*
X335000Y497000D03*
X332698Y543738D03*
X330200Y535200D03*
X331000Y522100D03*
X302665Y547006D03*
X302506Y543341D03*
X327403Y543499D03*
X336723Y542000D03*
X327800Y514900D03*
X330200Y531800D03*
X323400Y507540D03*
X336800Y506300D03*
X286061Y502378D03*
X293970Y564927D03*
X335000Y500600D03*
X298719Y542538D03*
X293500Y522600D03*
X334811Y551476D03*
X311900Y511500D03*
X309600Y520150D03*
X312300Y540600D03*
X332940Y539287D03*
X333400Y503800D03*
X322900Y530600D03*
X327417Y548344D03*
X290000Y503200D03*
X293800Y503300D03*
X299100Y589200D03*
X304124Y570227D03*
X341750Y630790D03*
X342330Y620300D03*
X344940Y617720D03*
X292400Y637000D03*
X341690Y609930D03*
X341210Y602420D03*
X330800Y602610D03*
X317572Y603183D03*
X305470Y623734D03*
X307542Y588138D03*
X334923Y579949D03*
X353500Y624500D03*
X353669Y600881D03*
X302300Y582000D03*
X286700Y611911D03*
X340920Y575234D03*
X348000Y612661D03*
X352472Y581000D03*
X325762Y596900D03*
X324900Y581600D03*
X291839Y578193D03*
X293697Y589566D03*
X289070Y573080D03*
X355700Y579317D03*
X341755Y627231D03*
Y623682D03*
X341600Y616962D03*
Y613413D03*
X334264Y602648D03*
X337813D03*
X352716Y594135D03*
X350746Y574837D03*
X293500Y625600D03*
X293600Y629100D03*
X321421Y605265D03*
X323413Y602491D03*
X303000Y586800D03*
X292006Y574797D03*
X315616Y571817D03*
X289800Y569182D03*
X315893Y567721D03*
X341558Y567689D03*
X300043Y603619D03*
X303468Y603647D03*
X352716Y590535D03*
X347784Y587509D03*
X336923Y586749D03*
X347784Y584109D03*
X336923Y583349D03*
X307650Y596000D03*
X285400Y572556D03*
X325761Y592959D03*
X315315Y575204D03*
X317813Y580469D03*
X286400Y569200D03*
X317813Y584969D03*
X325899Y589186D03*
X297118Y668882D03*
X294804Y695204D03*
X292400Y640500D03*
X332824Y684270D03*
X348314Y643853D03*
X332800Y691970D03*
X318000Y678270D03*
X304100Y666500D03*
X351547Y645938D03*
X355100Y651827D03*
X314398Y670254D03*
X340000Y662200D03*
X353700Y670900D03*
X352800Y702960D03*
X328356Y678679D03*
X297900Y664800D03*
X290600Y668200D03*
X338301Y673907D03*
X328600Y661100D03*
X343372Y655836D03*
X347013Y656090D03*
X328087Y701587D03*
X327062Y697600D03*
X332200Y643800D03*
X288720Y641455D03*
X289473Y657061D03*
X336000Y662200D03*
X336387Y648987D03*
X317516Y671612D03*
X315000Y674900D03*
X338135Y670511D03*
X342542Y685983D03*
X342645Y682506D03*
X300700Y667000D03*
X330593Y671019D03*
X303741Y654095D03*
X329989Y653920D03*
X298570Y743670D03*
X306470Y743570D03*
X291700Y737000D03*
X316465Y716063D03*
X287220Y737920D03*
X334000Y714640D03*
X293075Y726600D03*
X342208Y714950D03*
X337481Y719818D03*
X380500Y33500D03*
Y30000D03*
X382631Y48200D03*
X382547Y52800D03*
X375300Y62150D03*
X384000Y30000D03*
X425765Y56265D03*
X372500Y44500D03*
Y56500D03*
X375300Y72050D03*
X357500Y104200D03*
X394070Y80840D03*
X385964Y80089D03*
X382500Y88000D03*
X376000Y78400D03*
X366500Y124700D03*
X363100Y124600D03*
X387833Y82930D03*
X391382D03*
X372500Y90000D03*
Y78000D03*
X396800Y74800D03*
X405100Y159300D03*
X400000Y159200D03*
X365900Y198500D03*
X365800Y193750D03*
X399900Y152100D03*
X400924Y155896D03*
X404473D03*
X398000Y165400D03*
X398050Y162000D03*
X406400Y150300D03*
X362150Y214174D03*
X364000Y240100D03*
X363828Y243944D03*
X381009Y343909D03*
X380799Y347303D03*
X386250Y318250D03*
X380600Y335700D03*
X373700Y329700D03*
X376910Y366078D03*
X359323Y372277D03*
X363699Y382608D03*
X363703Y386008D03*
X363586Y375809D03*
X363701Y379208D03*
X377300Y362700D03*
X379448Y487250D03*
X361250Y491650D03*
X363942Y450591D03*
X366700Y454800D03*
X359400Y451600D03*
X381276Y469106D03*
X374030Y449526D03*
X372575Y452600D03*
X380200Y457800D03*
X381400Y462000D03*
X387500Y458200D03*
X370800Y475128D03*
X389081Y475224D03*
X387950Y466800D03*
X394700Y481700D03*
X394952Y485300D03*
X378937Y443491D03*
X376697Y446050D03*
X373576Y466300D03*
X373534Y462830D03*
X370900Y471700D03*
X373700Y482700D03*
X378200Y476600D03*
X377691Y451891D03*
X381370Y465500D03*
X388123Y492432D03*
X378840Y448690D03*
X361013Y475128D03*
X368100Y513100D03*
X387800Y529400D03*
X367500Y526800D03*
X393100Y564400D03*
X362801Y548097D03*
X366900Y499942D03*
X372714Y509275D03*
X364000Y525500D03*
X387400Y547500D03*
X384400Y545195D03*
X362666Y504265D03*
X390651Y499000D03*
X387800Y525500D03*
X387700Y521600D03*
X376617Y544817D03*
X397650Y508250D03*
Y536671D03*
X362280Y554590D03*
X397650Y519400D03*
X394880Y548670D03*
X397650Y523900D03*
X393465Y553100D03*
X387700Y517700D03*
X362500Y499970D03*
X365730Y541050D03*
X368900Y505000D03*
X372494Y513020D03*
X383126Y565162D03*
X366490Y564360D03*
X370763Y547900D03*
X370800Y551300D03*
Y554700D03*
X383080Y554897D03*
X384347Y558647D03*
X382922Y561735D03*
X372900Y538700D03*
X396400Y545500D03*
X390769Y495379D03*
X393889Y543207D03*
X396200Y597200D03*
X394800Y609700D03*
X358646Y596456D03*
X359000Y635600D03*
X360980Y582586D03*
X394300Y576600D03*
X372951Y576851D03*
X377714Y631280D03*
X368399Y567372D03*
X367133Y596067D03*
X382380Y612620D03*
X371180Y629236D03*
X386224Y580524D03*
X383411Y577024D03*
X362250Y570875D03*
X364300Y592900D03*
X384500Y616500D03*
X361227Y630300D03*
X378400Y594800D03*
X383313Y621780D03*
X365953Y570753D03*
X382600Y609000D03*
X375700Y580102D03*
X390600Y625500D03*
X366100Y590000D03*
X366500Y586300D03*
X380572Y592095D03*
X396300Y587000D03*
X396400Y583500D03*
X395127Y568056D03*
X395100Y572899D03*
X388418Y650549D03*
X385700Y641300D03*
X374200Y645871D03*
X374252Y641029D03*
X386050Y701200D03*
X379100Y703300D03*
X363664Y688950D03*
X384466Y661650D03*
X378832Y659705D03*
X364600Y670800D03*
X388338Y643600D03*
Y647149D03*
X392100Y683900D03*
X392000Y679800D03*
X390500Y665800D03*
Y669200D03*
X396306Y698732D03*
X361914Y680181D03*
X401000Y676500D03*
X371457Y667593D03*
X368060Y667743D03*
X392079Y703434D03*
X396400Y659800D03*
X390355Y690926D03*
X373060Y702960D03*
X398600Y662700D03*
X379450Y714400D03*
X383600Y711800D03*
X372100Y711700D03*
X478426Y20427D03*
X496394Y30000D03*
X482727Y41870D03*
X486535Y47449D03*
X482397Y52176D03*
X472800Y50000D03*
X469000Y50100D03*
X499721Y46102D03*
X499623Y49524D03*
X446788Y55180D03*
X479040Y47134D03*
X458041Y47341D03*
X476100Y60500D03*
X478700Y62800D03*
X462372Y49179D03*
X486400Y38500D03*
X467016Y20430D03*
X450454Y38147D03*
X486527Y41939D03*
X447233Y48829D03*
X496355Y26000D03*
X496242Y22287D03*
X460300Y57600D03*
X432269Y19980D03*
X486700Y31100D03*
X462874Y95922D03*
X487500Y73400D03*
X485700Y70500D03*
X448000Y80404D03*
X444800Y82404D03*
X478590Y70310D03*
X482200Y70500D03*
X498500Y84200D03*
X471281Y105681D03*
X455766Y114535D03*
X473600Y108300D03*
X457000Y117800D03*
X480538Y112071D03*
X459500Y95500D03*
X441100Y110950D03*
X448996Y117666D03*
X463479Y99412D03*
X504900Y18200D03*
X508646Y18386D03*
X518890Y59730D03*
X515700Y50899D03*
X515785Y55552D03*
X505633Y46932D03*
X502300Y58200D03*
X531050Y46998D03*
X528300Y58648D03*
X515500Y59000D03*
X513500Y62000D03*
X532500Y58600D03*
X513379Y103325D03*
X502379Y103194D03*
X543059Y108958D03*
X540800Y111500D03*
X501100Y86800D03*
X538456Y65144D03*
X509981Y103194D03*
X505779D03*
X513300Y83000D03*
X503700Y107600D03*
X599254Y37967D03*
X582447Y50607D03*
X588647Y28007D03*
X576649Y39585D03*
X575300Y45967D03*
X586754Y53967D03*
X577847Y50807D03*
X582797Y31807D03*
X600847Y33907D03*
X588753Y24080D03*
X603747Y71407D03*
X636647Y64300D03*
X642998Y127863D03*
X642574Y131843D03*
X710550Y18550D03*
X685907Y30622D03*
X673647Y33107D03*
X680300Y17500D03*
X680000Y23900D03*
X675903Y29541D03*
X668531Y71500D03*
X713200Y387700D03*
X700900Y423800D03*
X696070Y483486D03*
X712874Y470182D03*
X707391Y484208D03*
X712000Y442100D03*
X711300Y423800D03*
X701183Y453339D03*
X704836D03*
X709700Y480332D03*
X698651Y428165D03*
X669749Y458022D03*
X683000Y447200D03*
X680200Y449500D03*
X705450Y440950D03*
X705700Y493500D03*
X708367Y491000D03*
X715000Y547027D03*
X705853Y549017D03*
X708682Y551846D03*
X711156Y554320D03*
X713985Y557149D03*
X696624Y548249D03*
X699453Y551078D03*
X701927Y553552D03*
X704756Y556381D03*
X683369Y549269D03*
X686198Y552098D03*
X688672Y554572D03*
X691501Y557401D03*
X681989Y540183D03*
X684818Y543012D03*
X687292Y545486D03*
X690121Y548315D03*
X668195Y541742D03*
X671024Y544571D03*
X673498Y547045D03*
X676327Y549874D03*
X655092Y536171D03*
X657921Y539000D03*
X660395Y541474D03*
X663224Y544303D03*
X713189Y524511D03*
X707283D03*
X701378D03*
X695472D03*
X689567D03*
X683661D03*
X677756D03*
X662400Y519500D03*
X666800D03*
X657199Y530195D03*
X671850Y524511D03*
X653634Y513757D03*
X656846Y521702D03*
X678740Y508760D03*
X777500Y34500D03*
X766200Y22000D03*
X723800Y18600D03*
X725288Y405950D03*
X783800Y422800D03*
X718300Y387700D03*
X740500Y426800D03*
X716100Y442100D03*
X721100D03*
X725200D03*
X740500Y431000D03*
X723800Y475164D03*
X785434Y551934D03*
X788263Y554763D03*
X775934Y550934D03*
X778763Y553763D03*
X781237Y556237D03*
X784066Y559066D03*
X765434Y549934D03*
X768263Y552763D03*
X770737Y555237D03*
X773566Y558066D03*
X753434Y545434D03*
X756263Y548263D03*
X758737Y550737D03*
X761566Y553566D03*
X725853Y547117D03*
X728682Y549946D03*
X731156Y552420D03*
X733985Y555249D03*
X717829Y549856D03*
X720303Y552330D03*
X723132Y555159D03*
X716536Y523519D03*
X720536D03*
X724036D03*
X728036D03*
X762679Y535537D03*
X742716Y536435D03*
X738779D03*
X782086D03*
X776181D03*
X770275D03*
X725000D03*
X719394Y536305D03*
X759342Y543603D03*
X765935Y537009D03*
X777165Y509835D03*
X854596Y155288D03*
X840122Y156614D03*
X843160Y169467D03*
X845168Y192764D03*
X851137Y199864D03*
X858622Y155614D03*
X854634Y166390D03*
X842511Y164078D03*
X842022Y152174D03*
X858632Y216929D03*
X857700Y222300D03*
X848868Y219064D03*
X850730Y350483D03*
X841116Y348914D03*
X820059Y331701D03*
X835316Y340914D03*
X846456Y350814D03*
X808188Y404950D03*
X815541Y354089D03*
X847720Y371072D03*
X856720Y409372D03*
X809702Y416359D03*
X822300Y418900D03*
X831650Y422612D03*
X830531Y361589D03*
X794200Y422800D03*
X811300Y395900D03*
X801200Y386700D03*
X796100D03*
X821800Y400500D03*
X821700Y403900D03*
X842820Y382172D03*
X816997Y371022D03*
X847629Y391998D03*
X855320Y414472D03*
X830133Y353930D03*
X842916Y357214D03*
X849420Y407748D03*
X822300Y390000D03*
X804000Y441100D03*
X799000D03*
X811142Y470358D03*
X811668Y433703D03*
X820150Y433900D03*
X794900Y441100D03*
X808100D03*
X807400Y477229D03*
X823710Y469835D03*
X803300Y491600D03*
X806888Y491398D03*
X822434Y550434D03*
X825263Y553263D03*
X827737Y555737D03*
X830566Y558566D03*
X809934Y545434D03*
X812763Y548263D03*
X815237Y550737D03*
X818066Y553566D03*
X803934Y551934D03*
X806763Y554763D03*
X809237Y557237D03*
X812066Y560066D03*
X794934Y551434D03*
X797763Y554263D03*
X800237Y556737D03*
X803066Y559566D03*
X790737Y557237D03*
X793566Y560066D03*
X845198Y552063D03*
X842369Y549234D03*
X839895Y546760D03*
X837066Y543931D03*
X825000Y536200D03*
X817519Y536435D03*
X811614D03*
X805708D03*
X841141D03*
X837204D03*
X799803D03*
X793897D03*
X787992D03*
X867653Y172764D03*
X867851Y163585D03*
X864992Y175435D03*
X864492Y206435D03*
X860868Y219764D03*
X868433Y349134D03*
X864920Y368972D03*
X861420Y367269D03*
X861484Y399069D03*
G54D132*
G01X-9023Y-84471D02*
X-8149Y-83596D01*
X-7494Y-82138D01*
X-7057Y-80095D01*
X-7494Y-78346D01*
X-8367Y-77179D01*
X-9896Y-76304D01*
X-15791D01*
Y-93804D01*
X-8586D01*
X-7057Y-92638D01*
X-6184Y-90887D01*
X-5747Y-88846D01*
X-6184Y-86804D01*
X-7494Y-85054D01*
X-9023Y-84471D01*
X-15791D01*
G01X3674Y-93804D02*
Y-82138D01*
G01Y-84471D02*
X4766Y-83304D01*
X5858Y-82429D01*
X7386Y-82138D01*
X8477Y-82429D01*
X9788Y-83304D01*
G01X19646Y-99054D02*
X20956Y-99637D01*
X22703Y-99054D01*
X23794Y-97888D01*
X24668Y-96429D01*
X25977Y-91763D01*
X28816Y-82138D01*
G01X21829D02*
X25977Y-91763D01*
G01X45224Y-83596D02*
X43696Y-82429D01*
X42386Y-82138D01*
X40639Y-82721D01*
X39329Y-83887D01*
X38456Y-85929D01*
X38237Y-87971D01*
X38456Y-90013D01*
X39329Y-91763D01*
X40639Y-93221D01*
X42386Y-93804D01*
X43914Y-93221D01*
X45224Y-92054D01*
G01X55956Y-85929D02*
X62943D01*
X62288Y-83887D01*
X61196Y-82721D01*
X59668Y-82138D01*
X58139Y-82429D01*
X56829Y-83304D01*
X55956Y-85346D01*
X55519Y-87096D01*
Y-88846D01*
X55956Y-90596D01*
X57048Y-92346D01*
X58358Y-93512D01*
X59886Y-93804D01*
X61414Y-93221D01*
X62943Y-91471D01*
G01X99034Y-77763D02*
X97724Y-76887D01*
X96196Y-76304D01*
X94449D01*
X92484Y-77179D01*
X90956Y-78637D01*
X89864Y-80388D01*
X88991Y-83304D01*
X88772Y-85929D01*
X89209Y-88554D01*
X89864Y-90304D01*
X91174Y-92054D01*
X92703Y-93221D01*
X94231Y-93804D01*
X95759D01*
X97288Y-93221D01*
X98598Y-92346D01*
X99690Y-91180D01*
G01X115661Y-93804D02*
Y-82138D01*
G01Y-84179D02*
X114788Y-83013D01*
X113477Y-82429D01*
X111949Y-82138D01*
X110421Y-82721D01*
X109111Y-83887D01*
X108237Y-85637D01*
X107801Y-87971D01*
X108237Y-90304D01*
X109111Y-92054D01*
X110421Y-93221D01*
X111949Y-93804D01*
X113477Y-93512D01*
X114788Y-92638D01*
X115661Y-91471D01*
G01X125519Y-93804D02*
Y-82138D01*
G01Y-85054D02*
X126393Y-83596D01*
X127703Y-82429D01*
X129449Y-82138D01*
X130977Y-82429D01*
X132288Y-83596D01*
X132943Y-85637D01*
Y-93804D01*
G01X142146Y-99054D02*
X143456Y-99637D01*
X145203Y-99054D01*
X146294Y-97888D01*
X147168Y-96429D01*
X148477Y-91763D01*
X151316Y-82138D01*
G01X144329D02*
X148477Y-91763D01*
G01X164231Y-93804D02*
X162921Y-93512D01*
X161611Y-92346D01*
X160737Y-90304D01*
X160301Y-87971D01*
X160737Y-85637D01*
X161611Y-83596D01*
X162921Y-82429D01*
X164231Y-82138D01*
X165541Y-82429D01*
X166851Y-83596D01*
X167724Y-85637D01*
X167943Y-87971D01*
X167724Y-90304D01*
X166851Y-92346D01*
X165541Y-93512D01*
X164231Y-93804D01*
G01X178019D02*
Y-82138D01*
G01Y-85054D02*
X178893Y-83596D01*
X180203Y-82429D01*
X181949Y-82138D01*
X183477Y-82429D01*
X184788Y-83596D01*
X185443Y-85637D01*
Y-93804D01*
G01X214111Y-76304D02*
X219351D01*
G01X216731D02*
Y-93804D01*
G01X214111D02*
X219351D01*
G01X234231D02*
X232484Y-93512D01*
X230956Y-92346D01*
X229646Y-90596D01*
X228772Y-88554D01*
X228336Y-86221D01*
Y-83887D01*
X228772Y-81554D01*
X229646Y-79512D01*
X230956Y-77763D01*
X232484Y-76596D01*
X234231Y-76304D01*
X235977Y-76596D01*
X237506Y-77763D01*
X238816Y-79512D01*
X239690Y-81554D01*
X240126Y-83887D01*
Y-86221D01*
X239690Y-88554D01*
X238816Y-90596D01*
X237506Y-92346D01*
X235977Y-93512D01*
X234231Y-93804D01*
G01X246054D02*
Y-76304D01*
X251731Y-90887D01*
X257408Y-76304D01*
Y-93804D01*
G01X285639Y-99637D02*
X283456Y-96721D01*
X282364Y-93804D01*
Y-82138D01*
X283456Y-79221D01*
X285639Y-76304D01*
G01X298554Y-93804D02*
Y-76304D01*
X304231Y-90887D01*
X309908Y-76304D01*
Y-93804D01*
G01X321731Y-94387D02*
X321294Y-94096D01*
Y-93512D01*
X321731Y-93221D01*
X322168Y-93512D01*
Y-94096D01*
X321731Y-94387D01*
G01X335083Y-79221D02*
X336393Y-77471D01*
X337921Y-76596D01*
X339668Y-76304D01*
X341851Y-76887D01*
X343379Y-78346D01*
X343816Y-80095D01*
X343598Y-81846D01*
X342724Y-83304D01*
X338358Y-86221D01*
X336393Y-88262D01*
X335083Y-91180D01*
X334646Y-93804D01*
X343816D01*
G01X374231D02*
X372921Y-93512D01*
X371611Y-92346D01*
X370737Y-90304D01*
X370301Y-87971D01*
X370737Y-85637D01*
X371611Y-83596D01*
X372921Y-82429D01*
X374231Y-82138D01*
X375541Y-82429D01*
X376851Y-83596D01*
X377724Y-85637D01*
X377943Y-87971D01*
X377724Y-90304D01*
X376851Y-92346D01*
X375541Y-93512D01*
X374231Y-93804D01*
G01X388019D02*
Y-82138D01*
G01Y-85054D02*
X388893Y-83596D01*
X390203Y-82429D01*
X391949Y-82138D01*
X393477Y-82429D01*
X394788Y-83596D01*
X395443Y-85637D01*
Y-93804D01*
G01X409231D02*
Y-76304D01*
G01X422146Y-99054D02*
X423456Y-99637D01*
X425203Y-99054D01*
X426294Y-97888D01*
X427168Y-96429D01*
X428477Y-91763D01*
X431316Y-82138D01*
G01X424329D02*
X428477Y-91763D01*
G01X445323Y-99637D02*
X447506Y-96721D01*
X448598Y-93804D01*
Y-82138D01*
X447506Y-79221D01*
X445323Y-76304D01*
G01X176054Y-48804D02*
Y-31304D01*
X181731Y-45887D01*
X187408Y-31304D01*
Y-48804D01*
G01X199231D02*
X197921Y-48512D01*
X196611Y-47346D01*
X195737Y-45304D01*
X195301Y-42971D01*
X195737Y-40637D01*
X196611Y-38596D01*
X197921Y-37429D01*
X199231Y-37138D01*
X200541Y-37429D01*
X201851Y-38596D01*
X202724Y-40637D01*
X202943Y-42971D01*
X202724Y-45304D01*
X201851Y-47346D01*
X200541Y-48512D01*
X199231Y-48804D01*
G01X220661Y-31304D02*
Y-48804D01*
G01Y-46180D02*
X219788Y-47638D01*
X218477Y-48512D01*
X216949Y-48804D01*
X215203Y-48221D01*
X213893Y-46763D01*
X213019Y-45013D01*
X212801Y-42971D01*
X213019Y-40929D01*
X213893Y-39179D01*
X215203Y-37721D01*
X216949Y-37138D01*
X218477Y-37429D01*
X219569Y-38013D01*
X220661Y-39179D01*
G01X230956Y-40929D02*
X237943D01*
X237288Y-38887D01*
X236196Y-37721D01*
X234668Y-37138D01*
X233139Y-37429D01*
X231829Y-38304D01*
X230956Y-40346D01*
X230519Y-42096D01*
Y-43846D01*
X230956Y-45596D01*
X232048Y-47346D01*
X233358Y-48512D01*
X234886Y-48804D01*
X236414Y-48221D01*
X237943Y-46471D01*
G01X251731Y-48804D02*
Y-31304D01*
G01X504231Y-93804D02*
Y-76304D01*
X501611Y-79804D01*
G01Y-93804D02*
X506851D01*
G01X517583Y-86513D02*
X519111Y-84471D01*
X520421Y-83304D01*
X522168Y-82721D01*
X523696Y-83304D01*
X524788Y-84471D01*
X525661Y-86221D01*
X525879Y-88262D01*
X525661Y-90013D01*
X524788Y-91763D01*
X523477Y-93221D01*
X521949Y-93804D01*
X520203Y-93221D01*
X518674Y-91471D01*
X517801Y-88846D01*
X517583Y-85929D01*
X518019Y-82138D01*
X518674Y-80095D01*
X519766Y-78054D01*
X521294Y-76596D01*
X522823Y-76304D01*
X524351Y-76887D01*
X525443Y-78346D01*
G01X534428Y-90304D02*
X535737Y-92346D01*
X537484Y-93512D01*
X539449Y-93804D01*
X541196Y-93512D01*
X542943Y-92054D01*
X544034Y-90304D01*
X544253Y-88554D01*
X543816Y-86513D01*
X542288Y-85054D01*
X540759Y-84471D01*
X538794D01*
G01X540759D02*
X542069Y-83596D01*
X543161Y-82138D01*
X543598Y-80388D01*
X543161Y-78637D01*
X542069Y-77179D01*
X540104Y-76304D01*
X538139Y-76596D01*
X536174Y-77763D01*
G01X559351Y-93804D02*
Y-76304D01*
X551272Y-88846D01*
X562190D01*
G01X570083Y-79221D02*
X571393Y-77471D01*
X572921Y-76596D01*
X574668Y-76304D01*
X576851Y-76887D01*
X578379Y-78346D01*
X578816Y-80095D01*
X578598Y-81846D01*
X577724Y-83304D01*
X573358Y-86221D01*
X571393Y-88262D01*
X570083Y-91180D01*
X569646Y-93804D01*
X578816D01*
G01X491114Y-48804D02*
Y-31304D01*
X496354D01*
X498101Y-32179D01*
X499411Y-34221D01*
X499848Y-36554D01*
X499411Y-38887D01*
X498319Y-40637D01*
X496354Y-41513D01*
X491114D01*
G01X517784Y-32763D02*
X516474Y-31887D01*
X514946Y-31304D01*
X513199D01*
X511234Y-32179D01*
X509706Y-33637D01*
X508614Y-35388D01*
X507741Y-38304D01*
X507522Y-40929D01*
X507959Y-43554D01*
X508614Y-45304D01*
X509924Y-47054D01*
X511453Y-48221D01*
X512981Y-48804D01*
X514509D01*
X516038Y-48221D01*
X517348Y-47346D01*
X518440Y-46180D01*
G01X532227Y-39471D02*
X533101Y-38596D01*
X533756Y-37138D01*
X534193Y-35095D01*
X533756Y-33346D01*
X532883Y-32179D01*
X531354Y-31304D01*
X525459D01*
Y-48804D01*
X532664D01*
X534193Y-47638D01*
X535066Y-45887D01*
X535503Y-43846D01*
X535066Y-41804D01*
X533756Y-40054D01*
X532227Y-39471D01*
X525459D01*
G01X541431Y-54637D02*
X554531D01*
G01X560459Y-48804D02*
Y-31304D01*
X570503Y-48804D01*
Y-31304D01*
G01X582981Y-48804D02*
X581234Y-48512D01*
X579706Y-47346D01*
X578396Y-45596D01*
X577522Y-43554D01*
X577086Y-41221D01*
Y-38887D01*
X577522Y-36554D01*
X578396Y-34512D01*
X579706Y-32763D01*
X581234Y-31596D01*
X582981Y-31304D01*
X584727Y-31596D01*
X586256Y-32763D01*
X587566Y-34512D01*
X588440Y-36554D01*
X588876Y-38887D01*
Y-41221D01*
X588440Y-43554D01*
X587566Y-45596D01*
X586256Y-47346D01*
X584727Y-48512D01*
X582981Y-48804D01*
G01X633822Y-31304D02*
X639281Y-48804D01*
X644740Y-31304D01*
G01X661148Y-48804D02*
X652414D01*
Y-31304D01*
X661148D01*
G01X657654Y-39762D02*
X652414D01*
G01X669914Y-48804D02*
Y-31304D01*
X675373D01*
X677119Y-32179D01*
X678211Y-33346D01*
X678648Y-35679D01*
X678211Y-38013D01*
X676901Y-39471D01*
X675373Y-40346D01*
X669914D01*
G01X675373D02*
X678648Y-48804D01*
G01X691781Y-49387D02*
X691344Y-49096D01*
Y-48512D01*
X691781Y-48221D01*
X692218Y-48512D01*
Y-49096D01*
X691781Y-49387D01*
G01X661383Y-79221D02*
X662693Y-77471D01*
X664221Y-76596D01*
X665968Y-76304D01*
X668151Y-76887D01*
X669679Y-78346D01*
X670116Y-80095D01*
X669898Y-81846D01*
X669024Y-83304D01*
X664658Y-86221D01*
X662693Y-88262D01*
X661383Y-91180D01*
X660946Y-93804D01*
X670116D01*
G01X767364Y-31304D02*
Y-48804D01*
X776098D01*
G01X793161D02*
Y-37138D01*
G01Y-39179D02*
X792288Y-38013D01*
X790977Y-37429D01*
X789449Y-37138D01*
X787921Y-37721D01*
X786611Y-38887D01*
X785737Y-40637D01*
X785301Y-42971D01*
X785737Y-45304D01*
X786611Y-47054D01*
X787921Y-48221D01*
X789449Y-48804D01*
X790977Y-48512D01*
X792288Y-47638D01*
X793161Y-46471D01*
G01X802146Y-54054D02*
X803456Y-54637D01*
X805203Y-54054D01*
X806294Y-52888D01*
X807168Y-51429D01*
X808477Y-46763D01*
X811316Y-37138D01*
G01X804329D02*
X808477Y-46763D01*
G01X820956Y-40929D02*
X827943D01*
X827288Y-38887D01*
X826196Y-37721D01*
X824668Y-37138D01*
X823139Y-37429D01*
X821829Y-38304D01*
X820956Y-40346D01*
X820519Y-42096D01*
Y-43846D01*
X820956Y-45596D01*
X822048Y-47346D01*
X823358Y-48512D01*
X824886Y-48804D01*
X826414Y-48221D01*
X827943Y-46471D01*
G01X838674Y-48804D02*
Y-37138D01*
G01Y-39471D02*
X839766Y-38304D01*
X840858Y-37429D01*
X842386Y-37138D01*
X843477Y-37429D01*
X844788Y-38304D01*
G01X793614Y-76304D02*
Y-93804D01*
X802348D01*
G01X815481D02*
Y-76304D01*
X812861Y-79804D01*
G01Y-93804D02*
X818101D01*
G01X931781D02*
X930034Y-93512D01*
X928506Y-92346D01*
X927196Y-90596D01*
X926322Y-88554D01*
X925886Y-86221D01*
Y-83887D01*
X926322Y-81554D01*
X927196Y-79512D01*
X928506Y-77763D01*
X930034Y-76596D01*
X931781Y-76304D01*
X933527Y-76596D01*
X935056Y-77763D01*
X936366Y-79512D01*
X937240Y-81554D01*
X937676Y-83887D01*
Y-86221D01*
X937240Y-88554D01*
X936366Y-90596D01*
X935056Y-92346D01*
X933527Y-93512D01*
X931781Y-93804D01*
G01X933527Y-89137D02*
X936148Y-93804D01*
G01X944478Y-76304D02*
Y-88846D01*
X945351Y-91471D01*
X947098Y-93221D01*
X949281Y-93804D01*
X951464Y-93221D01*
X953211Y-91471D01*
X954084Y-88846D01*
Y-76304D01*
G01X964161D02*
X969401D01*
G01X966781D02*
Y-93804D01*
G01X964161D02*
X969401D01*
G01X979259D02*
Y-76304D01*
X989303Y-93804D01*
Y-76304D01*
G01X1006584Y-77763D02*
X1005274Y-76887D01*
X1003746Y-76304D01*
X1001999D01*
X1000034Y-77179D01*
X998506Y-78637D01*
X997414Y-80388D01*
X996541Y-83304D01*
X996322Y-85929D01*
X996759Y-88554D01*
X997414Y-90304D01*
X998724Y-92054D01*
X1000253Y-93221D01*
X1001781Y-93804D01*
X1003309D01*
X1004838Y-93221D01*
X1006148Y-92346D01*
X1007240Y-91180D01*
G01X1019281Y-93804D02*
Y-85929D01*
X1014914Y-76304D01*
G01X1023648D02*
X1019281Y-85929D01*
G01X909478Y-48804D02*
Y-31304D01*
X913844D01*
X915591Y-32179D01*
X916901Y-33346D01*
X917993Y-35095D01*
X918866Y-37138D01*
X919084Y-40054D01*
X918866Y-42971D01*
X917993Y-45013D01*
X916901Y-46763D01*
X915591Y-47929D01*
X913844Y-48804D01*
X909478D01*
G01X928506Y-40929D02*
X935493D01*
X934838Y-38887D01*
X933746Y-37721D01*
X932218Y-37138D01*
X930689Y-37429D01*
X929379Y-38304D01*
X928506Y-40346D01*
X928069Y-42096D01*
Y-43846D01*
X928506Y-45596D01*
X929598Y-47346D01*
X930908Y-48512D01*
X932436Y-48804D01*
X933964Y-48221D01*
X935493Y-46471D01*
G01X946006Y-46763D02*
X947098Y-47929D01*
X948626Y-48804D01*
X949936D01*
X951246Y-48221D01*
X952119Y-47346D01*
X952556Y-46180D01*
X952338Y-44429D01*
X951464Y-43554D01*
X947534Y-41804D01*
X946661Y-39762D01*
X947098Y-38304D01*
X947971Y-37429D01*
X949281Y-37138D01*
X950591Y-37429D01*
X951901Y-38304D01*
G01X966781Y-37138D02*
Y-48804D01*
G01Y-32471D02*
X966344Y-32179D01*
Y-31596D01*
X966781Y-31304D01*
X967218Y-31596D01*
Y-32179D01*
X966781Y-32471D01*
G01X981224Y-53179D02*
X982753Y-54346D01*
X984499Y-54637D01*
X986027Y-54346D01*
X987338Y-52888D01*
X988211Y-50846D01*
Y-37138D01*
G01Y-39471D02*
X987338Y-38304D01*
X986027Y-37429D01*
X984499Y-37138D01*
X982753Y-37721D01*
X981661Y-38887D01*
X980787Y-40929D01*
X980351Y-42971D01*
X980569Y-44721D01*
X981443Y-46763D01*
X982753Y-48221D01*
X984499Y-48804D01*
X985809Y-48512D01*
X987338Y-47346D01*
X988211Y-46180D01*
G01X998069Y-48804D02*
Y-37138D01*
G01Y-40054D02*
X998943Y-38596D01*
X1000253Y-37429D01*
X1001999Y-37138D01*
X1003527Y-37429D01*
X1004838Y-38596D01*
X1005493Y-40637D01*
Y-48804D01*
G01X1016006Y-40929D02*
X1022993D01*
X1022338Y-38887D01*
X1021246Y-37721D01*
X1019718Y-37138D01*
X1018189Y-37429D01*
X1016879Y-38304D01*
X1016006Y-40346D01*
X1015569Y-42096D01*
Y-43846D01*
X1016006Y-45596D01*
X1017098Y-47346D01*
X1018408Y-48512D01*
X1019936Y-48804D01*
X1021464Y-48221D01*
X1022993Y-46471D01*
G01X1033724Y-48804D02*
Y-37138D01*
G01Y-39471D02*
X1034816Y-38304D01*
X1035908Y-37429D01*
X1037436Y-37138D01*
X1038527Y-37429D01*
X1039838Y-38304D01*
G01X1080481Y-76304D02*
X1078734Y-76887D01*
X1077424Y-78346D01*
X1076551Y-80095D01*
X1075896Y-82429D01*
X1075678Y-85054D01*
X1075896Y-87679D01*
X1076551Y-90013D01*
X1077424Y-91763D01*
X1078734Y-93221D01*
X1080481Y-93804D01*
X1082227Y-93221D01*
X1083538Y-91763D01*
X1084411Y-90013D01*
X1085066Y-87679D01*
X1085284Y-85054D01*
X1085066Y-82429D01*
X1084411Y-80095D01*
X1083538Y-78346D01*
X1082227Y-76887D01*
X1080481Y-76304D01*
G01X1097981Y-93804D02*
X1099509Y-93512D01*
X1101256Y-92638D01*
X1102348Y-91180D01*
X1102784Y-89137D01*
X1102348Y-87096D01*
X1101038Y-85346D01*
X1099073Y-84471D01*
X1096889D01*
X1095579Y-83887D01*
X1094487Y-82429D01*
X1094051Y-80388D01*
X1094706Y-78346D01*
X1096234Y-76887D01*
X1097981Y-76304D01*
X1099727Y-76887D01*
X1101256Y-78346D01*
X1101911Y-80388D01*
X1101474Y-82429D01*
X1100383Y-83887D01*
X1099073Y-84471D01*
X1096889D01*
X1094924Y-85346D01*
X1093614Y-87096D01*
X1093178Y-89137D01*
X1093614Y-91180D01*
X1094706Y-92638D01*
X1096453Y-93512D01*
X1097981Y-93804D01*
G01X1111551Y-94387D02*
X1119411Y-76304D01*
G01X1132981D02*
X1131234Y-76887D01*
X1129924Y-78346D01*
X1129051Y-80095D01*
X1128396Y-82429D01*
X1128178Y-85054D01*
X1128396Y-87679D01*
X1129051Y-90013D01*
X1129924Y-91763D01*
X1131234Y-93221D01*
X1132981Y-93804D01*
X1134727Y-93221D01*
X1136038Y-91763D01*
X1136911Y-90013D01*
X1137566Y-87679D01*
X1137784Y-85054D01*
X1137566Y-82429D01*
X1136911Y-80095D01*
X1136038Y-78346D01*
X1134727Y-76887D01*
X1132981Y-76304D01*
G01X1150044Y-93804D02*
X1150481Y-90013D01*
X1151136Y-86804D01*
X1152009Y-83887D01*
X1153101Y-80679D01*
X1154848Y-76304D01*
X1146114D01*
G01X1164051Y-94387D02*
X1171911Y-76304D01*
G01X1181333Y-79221D02*
X1182643Y-77471D01*
X1184171Y-76596D01*
X1185918Y-76304D01*
X1188101Y-76887D01*
X1189629Y-78346D01*
X1190066Y-80095D01*
X1189848Y-81846D01*
X1188974Y-83304D01*
X1184608Y-86221D01*
X1182643Y-88262D01*
X1181333Y-91180D01*
X1180896Y-93804D01*
X1190066D01*
G01X1202981Y-76304D02*
X1201234Y-76887D01*
X1199924Y-78346D01*
X1199051Y-80095D01*
X1198396Y-82429D01*
X1198178Y-85054D01*
X1198396Y-87679D01*
X1199051Y-90013D01*
X1199924Y-91763D01*
X1201234Y-93221D01*
X1202981Y-93804D01*
X1204727Y-93221D01*
X1206038Y-91763D01*
X1206911Y-90013D01*
X1207566Y-87679D01*
X1207784Y-85054D01*
X1207566Y-82429D01*
X1206911Y-80095D01*
X1206038Y-78346D01*
X1204727Y-76887D01*
X1202981Y-76304D01*
G01X1220481Y-93804D02*
Y-76304D01*
X1217861Y-79804D01*
G01Y-93804D02*
X1223101D01*
G01X1237544D02*
X1237981Y-90013D01*
X1238636Y-86804D01*
X1239509Y-83887D01*
X1240601Y-80679D01*
X1242348Y-76304D01*
X1233614D01*
G01X1128178Y-48804D02*
Y-31304D01*
X1132544D01*
X1134291Y-32179D01*
X1135601Y-33346D01*
X1136693Y-35095D01*
X1137566Y-37138D01*
X1137784Y-40054D01*
X1137566Y-42971D01*
X1136693Y-45013D01*
X1135601Y-46763D01*
X1134291Y-47929D01*
X1132544Y-48804D01*
X1128178D01*
G01X1154411D02*
Y-37138D01*
G01Y-39179D02*
X1153538Y-38013D01*
X1152227Y-37429D01*
X1150699Y-37138D01*
X1149171Y-37721D01*
X1147861Y-38887D01*
X1146987Y-40637D01*
X1146551Y-42971D01*
X1146987Y-45304D01*
X1147861Y-47054D01*
X1149171Y-48221D01*
X1150699Y-48804D01*
X1152227Y-48512D01*
X1153538Y-47638D01*
X1154411Y-46471D01*
G01X1167981Y-31304D02*
Y-48804D01*
G01X1164924Y-37138D02*
X1171038D01*
G01X1182206Y-40929D02*
X1189193D01*
X1188538Y-38887D01*
X1187446Y-37721D01*
X1185918Y-37138D01*
X1184389Y-37429D01*
X1183079Y-38304D01*
X1182206Y-40346D01*
X1181769Y-42096D01*
Y-43846D01*
X1182206Y-45596D01*
X1183298Y-47346D01*
X1184608Y-48512D01*
X1186136Y-48804D01*
X1187664Y-48221D01*
X1189193Y-46471D01*
G54D105*
X544495Y54351D03*
Y47945D03*
G54D123*
X851518Y192564D03*
G54D30*
X45052Y659909D03*
X182637Y463761D03*
X211800Y626900D03*
X148649Y687715D03*
X271900Y465400D03*
X258558Y589579D03*
X250525Y633776D03*
X275803Y704337D03*
X278200Y640772D03*
X263100Y666000D03*
X351282Y189778D03*
X293695Y539294D03*
X319600Y526100D03*
X284970Y637250D03*
X331800Y581394D03*
Y585000D03*
X389100Y541100D03*
X391011Y577031D03*
X370214Y639820D03*
X386100Y698000D03*
X379500Y710400D03*
X483026Y55778D03*
X493300Y38000D03*
X472386Y53022D03*
X552800Y61200D03*
X617847Y63107D03*
G54D12*
X55300Y45000D03*
X33265Y532638D03*
X61454Y639950D03*
X39754Y679750D03*
X95068Y55255D03*
X133277Y613060D03*
X131262Y603311D03*
X134249Y599062D03*
X132295Y617354D03*
X114271Y596454D03*
X106249Y599764D03*
Y607964D03*
Y603864D03*
Y612064D03*
Y624364D03*
Y620264D03*
X109899Y701465D03*
X137649Y687715D03*
X179063Y459780D03*
Y469880D03*
X268000Y470300D03*
Y458200D03*
X268400Y489500D03*
X237863Y539142D03*
X245428Y536660D03*
X215800Y512066D03*
X243238Y528501D03*
X235709Y524700D03*
X235600Y520563D03*
X267700Y605800D03*
X238858Y581690D03*
X240200Y585700D03*
X241142Y572585D03*
X238625Y568522D03*
X253560Y593575D03*
X256882Y642199D03*
X274700Y644572D03*
X265800Y639500D03*
X271990Y723570D03*
X340348Y228017D03*
X347961Y251004D03*
Y247004D03*
X347962Y242193D03*
X344482Y265778D03*
X289600Y551300D03*
X289355Y546706D03*
X347800Y511900D03*
Y500200D03*
X334804Y559544D03*
X334864Y555473D03*
X334795Y563788D03*
X323800Y526000D03*
X302000Y616384D03*
X344300Y581000D03*
X334755Y567922D03*
X334799Y572721D03*
X332553Y576849D03*
X321475Y678443D03*
X291318Y684153D03*
X334723Y677472D03*
X320083Y674407D03*
X389536Y585080D03*
X389200Y637900D03*
X389500Y589100D03*
X389236Y628580D03*
X389600Y605400D03*
X387836Y617980D03*
X389500Y593200D03*
X389600Y601300D03*
X388195Y568431D03*
X388244Y572999D03*
X386102Y694223D03*
X385400Y683900D03*
X385300Y679800D03*
Y675600D03*
X434185Y38057D03*
X442585Y21957D03*
X435858Y56153D03*
X442685Y30457D03*
Y26157D03*
X442616Y38147D03*
X489800Y30000D03*
X489700Y21800D03*
X489800Y26000D03*
X527600Y54648D03*
X527597Y50148D03*
X618596Y55138D03*
X581904Y41467D03*
X579347Y37207D03*
X650383Y525811D03*
X733800Y431000D03*
X851222Y149514D03*
X846611Y169478D03*
X848968Y203864D03*
Y215964D03*
X836239Y356008D03*
X836213Y360311D03*
X836216Y351914D03*
X816700Y430000D03*
X863630Y215262D03*
G54D21*
X30900Y79600D03*
X81169Y734566D03*
X145053Y647840D03*
X271068Y529401D03*
X847271Y45720D03*
G54D114*
X673647Y35657D03*
Y36157D03*
X904262Y71265D03*
Y71765D03*
G54D133*
G01X211750Y626900D02*
Y629050D01*
X210450Y630350D01*
Y630600D01*
G01X204843Y623300D02*
X203700Y622157D01*
Y616775D01*
X205650Y614825D01*
Y613250D01*
X198819Y606419D01*
Y603937D01*
G01X204843Y623300D02*
X208150D01*
X211750Y626900D01*
G01X208200Y634100D02*
X206950Y632850D01*
Y630600D01*
G01X200000Y618900D02*
Y629381D01*
X202019Y631400D01*
X205680D01*
X206480Y630600D01*
X206950D01*
G01X200000Y618900D02*
Y616800D01*
X201900Y614900D01*
Y613100D01*
X197300Y608500D01*
Y602306D01*
X198819Y600787D01*
G01X194094Y602362D02*
X195669Y603937D01*
G01X194093Y596063D02*
Y596062D01*
X192519Y594488D01*
G01X191578Y643963D02*
Y647278D01*
X193000Y648700D01*
G01D02*
X194100D01*
X195600Y647200D01*
Y646000D01*
G54D31*
X64884Y643900D03*
X48284Y671800D03*
X211750Y634100D03*
X210500Y630600D03*
X148700Y691600D03*
X147417Y740048D03*
X275620Y715620D03*
X287000Y531100D03*
X305670Y612350D03*
X322300Y599000D03*
X288495Y576463D03*
X294804Y688120D03*
X286170Y644150D03*
X374104Y197291D03*
X362586Y639880D03*
X446135Y34357D03*
X707700Y423800D03*
X790600Y422800D03*
G54D40*
X123586Y460300D03*
Y465300D03*
Y470300D03*
Y475300D03*
Y480300D03*
Y485300D03*
Y490300D03*
Y495300D03*
X162144Y490300D03*
Y485300D03*
Y480300D03*
Y475300D03*
Y470300D03*
Y465300D03*
Y460300D03*
Y495300D03*
X220521Y460300D03*
Y465300D03*
Y470300D03*
Y475300D03*
Y480300D03*
Y485300D03*
Y490300D03*
X259079D03*
Y485300D03*
Y480300D03*
Y475300D03*
Y470300D03*
Y465300D03*
Y460300D03*
X220521Y495300D03*
X259079D03*
G54D106*
X531093Y39133D03*
Y34133D03*
Y29133D03*
Y24133D03*
G54D115*
X714454Y422965D03*
Y406785D03*
X717014Y422965D03*
X719574D03*
X722134D03*
Y406785D03*
X719574D03*
X717014D03*
X797354Y421965D03*
X799914D03*
X802474D03*
X805034D03*
Y405785D03*
X802474D03*
X799914D03*
X797354D03*
G54D124*
X856271Y393042D03*
X858240D03*
Y373756D03*
X856271D03*
X859779Y200908D03*
X861748D03*
X863716D03*
X865685D03*
X867653D03*
X869622D03*
X871591D03*
X873559D03*
X875528D03*
X877496D03*
X879465D03*
Y181622D03*
X877496D03*
X875528D03*
X873559D03*
X871591D03*
X869622D03*
X867653D03*
X865685D03*
X863716D03*
X861748D03*
X859779D03*
X860208Y393042D03*
X862177D03*
X864145D03*
X866114D03*
X868083D03*
X870051D03*
X872020D03*
X873988D03*
X875957D03*
Y373756D03*
X873988D03*
X872020D03*
X870051D03*
X868083D03*
X866114D03*
X864145D03*
X862177D03*
X860208D03*
G54D13*
X58700Y45000D03*
X36665Y532638D03*
X64854Y639950D03*
X43154Y679750D03*
X98468Y55255D03*
X136677Y613060D03*
X134662Y603311D03*
X137649Y599062D03*
X135695Y617354D03*
X117671Y596454D03*
X109649Y599764D03*
Y607964D03*
Y603864D03*
Y612064D03*
Y624364D03*
Y620264D03*
X113299Y701465D03*
X141049Y687715D03*
X182463Y459780D03*
Y469880D03*
X271400Y470300D03*
Y458200D03*
X271800Y489500D03*
X241263Y539142D03*
X248828Y536660D03*
X219200Y512066D03*
X246638Y528501D03*
X239109Y524700D03*
X239000Y520563D03*
X271100Y605800D03*
X242258Y581690D03*
X243600Y585700D03*
X244542Y572585D03*
X242025Y568522D03*
X256960Y593575D03*
X260282Y642199D03*
X278100Y644572D03*
X269200Y639500D03*
X275390Y723570D03*
X343748Y228017D03*
X351361Y251004D03*
Y247004D03*
X351362Y242193D03*
X347882Y265778D03*
X293000Y551300D03*
X292755Y546706D03*
X351200Y511900D03*
Y500200D03*
X338204Y559544D03*
X338264Y555473D03*
X338195Y563788D03*
X327200Y526000D03*
X305400Y616384D03*
X347700Y581000D03*
X338155Y567922D03*
X338199Y572721D03*
X335953Y576849D03*
X324875Y678443D03*
X294718Y684153D03*
X338123Y677472D03*
X323483Y674407D03*
X392936Y585080D03*
X392600Y637900D03*
X392900Y589100D03*
X392636Y628580D03*
X393000Y605400D03*
X391236Y617980D03*
X392900Y593200D03*
X393000Y601300D03*
X391595Y568431D03*
X391644Y572999D03*
X389502Y694223D03*
X388800Y683900D03*
X388700Y679800D03*
Y675600D03*
X437585Y38057D03*
X445985Y21957D03*
X439258Y56153D03*
X446085Y30457D03*
Y26157D03*
X446016Y38147D03*
X493200Y30000D03*
X493100Y21800D03*
X493200Y26000D03*
X531000Y54648D03*
X530997Y50148D03*
X621996Y55138D03*
X585304Y41467D03*
X582747Y37207D03*
X653783Y525811D03*
X737200Y431000D03*
X854622Y149514D03*
X850011Y169478D03*
X852368Y203864D03*
Y215964D03*
X839639Y356008D03*
X839613Y360311D03*
X839616Y351914D03*
X820100Y430000D03*
X867030Y215262D03*
G54D22*
G01X58750Y45000D02*
Y48750D01*
X62000Y52000D01*
G01X58750Y45000D02*
Y36723D01*
X61024Y34449D01*
G01X277455Y446150D02*
X271163D01*
X268013Y449300D01*
X235300D01*
X232100Y452500D01*
X221700D01*
X216600Y447400D01*
X161108D01*
X160143Y446435D01*
X66607D01*
X20118Y492924D01*
Y667030D01*
X28971Y675883D01*
G01X66278Y547093D02*
X61493D01*
X61100Y546700D01*
G01X69427Y581738D02*
X67852Y583313D01*
G01X63155Y656107D02*
Y652713D01*
X64884Y650984D01*
G01X39704Y679750D02*
X32838D01*
X28971Y675883D01*
G01X86028Y689689D02*
X83476Y687137D01*
X79438D01*
X76825Y684524D01*
X67490D01*
X63155Y680189D01*
Y675593D01*
G01X73427Y689785D02*
X70912Y687270D01*
X66700D01*
X60596Y681166D01*
Y675593D01*
G01X43204Y679750D02*
X43700Y679254D01*
Y675900D01*
X43800Y675800D01*
G01X48234Y671800D02*
Y675500D01*
X48200Y675534D01*
G01X48234Y671800D02*
X49066Y670968D01*
X55971D01*
G01X43800Y675800D02*
X44100Y675500D01*
X48166D01*
X48200Y675534D01*
G01X49500Y659909D02*
X52720D01*
X53543Y660732D01*
X55971D01*
G01X45002Y659909D02*
X49500D01*
G01X98518Y55255D02*
X98468Y55205D01*
X102844Y50829D01*
Y49716D01*
X108268Y44292D01*
G01X98518Y55255D02*
Y59005D01*
X101768Y62255D01*
G01X91474Y556542D02*
X91472D01*
X89899Y558115D01*
G01X91474Y578589D02*
Y578588D01*
X93048Y577014D01*
G01X72577Y572290D02*
X75050D01*
X75197Y572437D01*
G01X113349Y701465D02*
X117865D01*
X118477Y702077D01*
G01X113349Y701465D02*
Y697097D01*
G01X118477Y702077D02*
X118849Y702449D01*
Y705549D01*
X122239Y708939D01*
X125376D01*
G01X106879Y707245D02*
X108595D01*
X111200Y709850D01*
G01X125376Y705002D02*
Y701124D01*
G01D02*
Y695876D01*
X123797Y694297D01*
X121449D01*
G01X122100Y698500D02*
X120697Y697097D01*
X117349D01*
G01X122100Y698500D02*
Y701801D01*
X121501Y702400D01*
Y705367D01*
X123105Y706971D01*
X125376D01*
G01X109849Y701465D02*
X106635D01*
G01X86028Y689689D02*
X89303D01*
X89868Y689124D01*
G01X77903Y689785D02*
X73427D01*
G01X81928Y689789D02*
X77907D01*
X77903Y689785D01*
G01X115619Y712995D02*
X115738Y712876D01*
X125376D01*
G01X111200Y713350D02*
X115264D01*
X115619Y712995D01*
G01X111200Y713350D02*
X108960D01*
X106355Y710745D01*
G01X125376Y710908D02*
X121042D01*
X119849Y709715D01*
G01X186220Y540945D02*
X184645Y539370D01*
G01D02*
X186220Y537795D01*
G01X192519Y540945D02*
X194094Y539370D01*
G01D02*
X192519Y537795D01*
G01X197243Y539371D02*
X195669Y537797D01*
Y537795D01*
G01X194093Y555120D02*
X194092D01*
X192519Y556693D01*
G01X181497Y555120D02*
X183070Y556693D01*
X183071D01*
G01X179921D02*
X179924D01*
X181497Y555120D01*
G01X176771Y556693D02*
X176772D01*
X178346Y555119D01*
G01X187885Y552058D02*
X189370Y553543D01*
G01X197245Y555118D02*
X198819Y556692D01*
Y556693D01*
G01X195669D02*
X195670D01*
X197245Y555118D01*
G01X178347Y564569D02*
X179921Y562995D01*
Y562992D01*
G01Y566142D02*
X179920D01*
X178347Y564569D01*
G01X203543Y561418D02*
X203542D01*
X201968Y562992D01*
G01Y559842D02*
Y559843D01*
X203543Y561418D01*
G01Y564568D02*
X203542D01*
X201968Y566142D01*
G01X154724Y603937D02*
X153996Y604665D01*
Y604666D01*
X153149Y605513D01*
G01X203605Y605821D02*
Y605592D01*
X203463Y605450D01*
G01X157874Y566142D02*
X159449Y567717D01*
G01X186220Y594488D02*
X186595Y594863D01*
Y597263D01*
X186220Y597638D01*
G01Y600787D02*
X187795Y602362D01*
Y602363D01*
G01D02*
X187794D01*
X186220Y603937D01*
G01X208267Y591338D02*
X206692Y592913D01*
G01X205118Y575590D02*
X205116D01*
X203543Y574017D01*
G01X178347Y574018D02*
X179921Y572444D01*
Y572441D01*
G01Y575590D02*
X179919D01*
X178347Y574018D01*
G01X203542Y580315D02*
X201968Y578741D01*
Y578740D01*
G01Y581890D02*
Y581889D01*
X203542Y580315D01*
G01Y586614D02*
X201968Y585040D01*
Y585039D01*
G01X205118Y588189D02*
X205117D01*
X203542Y586614D01*
G01X189370Y585039D02*
X190944Y586613D01*
Y586614D01*
G01X179921Y585039D02*
Y585040D01*
X178346Y586615D01*
G01D02*
X176771Y585040D01*
Y585039D01*
G01X183071D02*
Y585040D01*
X181497Y586614D01*
G01X179921Y578740D02*
X179918D01*
X178344Y577166D01*
G01X201968Y575590D02*
Y575591D01*
X203542Y577165D01*
G01X178347Y570769D02*
X179921Y569195D01*
Y569291D01*
G01X203501Y571005D02*
Y570825D01*
X201968Y569292D01*
Y569291D01*
G01X203501Y571005D02*
X203403D01*
X201968Y572440D01*
Y572441D01*
G01X188500Y690050D02*
Y686800D01*
G01X151749Y699165D02*
X150335D01*
X148349Y701151D01*
Y706215D01*
X147593Y706971D01*
X144662D01*
G01X155849Y699165D02*
X151749D01*
G01X164249D02*
X160200D01*
G01D02*
X155849D01*
G01X158304Y726775D02*
X167347D01*
X169147Y724975D01*
Y709625D01*
X168047Y708525D01*
G01X148650Y691600D02*
X151834D01*
X151949Y691715D01*
G01X168047Y705025D02*
X171647D01*
X171747Y704925D01*
G01D02*
X176447D01*
G01X180190Y726775D02*
X172547D01*
X170947Y725175D01*
Y709225D01*
X171747Y708425D01*
G01X145099Y683715D02*
X145061Y683677D01*
X142681D01*
X141099Y685259D01*
Y687715D01*
G01X145099D02*
Y683715D01*
G01X145150Y691600D02*
Y687766D01*
X145099Y687715D01*
G01X145150Y691600D02*
X143100Y693650D01*
Y696800D01*
G01D02*
X144662Y698362D01*
Y705002D01*
G01X148599Y683715D02*
Y687715D01*
G01D02*
X164849D01*
X168949Y691815D01*
G01X162700Y703500D02*
X162665Y703465D01*
X158349D01*
G01Y706965D02*
X154300D01*
G01X162360Y706888D02*
X162283Y706965D01*
X158349D01*
G01X154300D02*
X150599D01*
X148625Y708939D01*
X144662D01*
G01X164249Y695665D02*
X167504D01*
X168273Y696434D01*
G01X155099Y711215D02*
X153849D01*
X152188Y712876D01*
X144662D01*
G01X150849Y710215D02*
X150156Y710908D01*
X144662D01*
G01X295700Y428400D02*
Y436200D01*
X289300Y442600D01*
X268700D01*
X265400Y445900D01*
Y446100D01*
G01X222500Y536161D02*
X220866Y537795D01*
G01X243750Y589800D02*
X243950Y589600D01*
X246800D01*
G01X222440Y605512D02*
X220866Y603938D01*
Y603937D01*
G01X270300Y622315D02*
Y618736D01*
X270521Y618515D01*
G01X254821Y627000D02*
X255610Y626211D01*
Y625611D01*
X256625Y624596D01*
X258823D01*
G01X262823Y624646D02*
X258873D01*
X258823Y624596D01*
G01X245971Y692774D02*
Y698400D01*
G01X221575Y688956D02*
Y695400D01*
G01X243731Y702324D02*
Y700640D01*
X245971Y698400D01*
G01X285773Y657061D02*
X285561D01*
X282620Y654120D01*
Y652044D01*
G01X279920Y703460D02*
X276630D01*
X275753Y704337D01*
G01X285891Y704952D02*
X281412D01*
X279920Y703460D01*
G01X271940Y723570D02*
X268230D01*
G01X287620Y730170D02*
X283298D01*
X283032Y730436D01*
G01X275570Y715620D02*
Y719320D01*
X275470Y719420D01*
G01X279900Y715400D02*
X275790D01*
X275570Y715620D01*
G01X279900Y715400D02*
X282088D01*
X282300Y715188D01*
X285891D01*
G01X275440Y723570D02*
Y719450D01*
X275470Y719420D01*
G01X354000Y116000D02*
X349500D01*
X348900Y115400D01*
G01X351532Y178678D02*
X352154Y179300D01*
X355300D01*
G01X314666Y214764D02*
X319932D01*
X323842Y218674D01*
Y219284D01*
G01X314666Y217913D02*
X319801D01*
X321172Y219284D01*
X323842D01*
G01X297146Y214764D02*
X303292D01*
X304232Y213824D01*
X305498D01*
G01X297146Y211614D02*
X303288D01*
X305498Y213824D01*
G01X297146Y249410D02*
X303546D01*
X305082Y247874D01*
X306446D01*
G01X314666Y378543D02*
X319463D01*
X320932Y377074D01*
G01X355700Y510000D02*
Y510280D01*
X356489Y511069D01*
X361439D01*
G01X348550Y543800D02*
X350300Y542050D01*
X352510D01*
X352734Y541826D01*
G01X362801Y548097D02*
X362253Y547549D01*
X355739D01*
G01X304800Y554443D02*
X299124D01*
G01X303741Y628857D02*
Y625463D01*
X305470Y623734D01*
G01X353669Y600881D02*
X353758Y600970D01*
X357290D01*
G01X348000Y612661D02*
X348041Y612620D01*
X353864D01*
G01X288771Y637726D02*
X285396D01*
X284920Y637250D01*
G01X288771Y637726D02*
Y637111D01*
X292400Y633482D01*
X296557D01*
G01X294804Y695204D02*
X293075Y696933D01*
Y700327D01*
G01X352100Y673680D02*
Y672500D01*
X353700Y670900D01*
G01X357800Y706700D02*
X341939D01*
X339304Y709335D01*
G01D02*
X334000Y714639D01*
Y714640D01*
G01X289473Y657061D02*
X285773D01*
G01X294018Y655000D02*
X296118Y652900D01*
X299500D01*
X301182Y651218D01*
Y648343D01*
G01X289612Y661479D02*
X292321D01*
X294018Y659782D01*
G01D02*
Y655000D01*
G01X286120Y647978D02*
Y652044D01*
G01X296557Y643718D02*
X293582D01*
X292600Y644700D01*
X290500D01*
G01D02*
X288762D01*
X288212Y644150D01*
X286120D01*
G01D02*
Y647978D01*
G01X293075Y726600D02*
Y728775D01*
X291700Y730150D01*
G01X293075Y719813D02*
Y726600D01*
G01X287620Y730170D02*
Y726420D01*
X287600Y726400D01*
G01D02*
Y724400D01*
X290516Y721484D01*
Y719813D01*
G01X375260Y487250D02*
X379448D01*
G01X364600Y495450D02*
Y497642D01*
X366900Y499942D01*
G01X359036Y639880D02*
Y635636D01*
X359000Y635600D01*
G01X358646Y596456D02*
Y597600D01*
X359258Y598212D01*
Y601320D01*
G01X367133D02*
Y596067D01*
G01X376464Y612620D02*
X382380D01*
G01X371180Y629236D02*
X371070Y629126D01*
Y623920D01*
G01X374252Y641029D02*
X371373D01*
X370164Y639820D01*
G01X493250Y30000D02*
X496394D01*
G01X482727Y41870D02*
X481178Y40321D01*
X477750D01*
G01X493250Y30000D02*
Y33600D01*
X493650Y34000D01*
G01X477750Y38353D02*
X474853D01*
X472000Y35500D01*
G01X479040Y47134D02*
X478050Y46144D01*
Y42290D01*
G01X464342Y53808D02*
X460489D01*
X460442Y53761D01*
G01X464342Y53808D02*
Y50905D01*
X465047Y50200D01*
Y45150D01*
G01X456288Y54522D02*
X459681D01*
X460442Y53761D01*
G01X459500Y95500D02*
X455300D01*
X442850Y107950D01*
Y109068D01*
X442849Y109069D01*
Y109201D01*
X441100Y110950D01*
G01X599898Y42014D02*
Y38611D01*
X599254Y37967D01*
G01X585970Y50435D02*
X582619D01*
X582447Y50607D01*
G01X588647Y35907D02*
Y39260D01*
X589104Y39717D01*
G01X599254Y37967D02*
X593733D01*
X591983Y39717D01*
X589104D01*
G01X588647Y31707D02*
Y28007D01*
G01X641347Y57207D02*
Y56247D01*
X639747Y54647D01*
Y44407D01*
X641447Y42707D01*
G01D02*
X646021D01*
G01X586647Y57257D02*
Y54074D01*
X586754Y53967D01*
G01X590347Y57257D02*
X586647D01*
G01X589470Y50435D02*
X589542Y50507D01*
X595647D01*
X598234Y47920D01*
X599898D01*
G01X589470Y50435D02*
Y50984D01*
X586754Y53700D01*
Y53967D01*
G01X636647Y60357D02*
X638497D01*
X641347Y63207D01*
G01X636647Y64300D02*
Y60357D01*
G01X577847Y50807D02*
X577404Y51250D01*
Y54767D01*
G01X586647Y60757D02*
X590347D01*
G01D02*
X590387Y60717D01*
X594504D01*
G01X586647Y60757D02*
X582232D01*
G01D02*
X577414D01*
X577404Y60767D01*
G01X603247Y30307D02*
X598656D01*
G01X605020Y38911D02*
Y32080D01*
X603247Y30307D01*
G01X594541Y33031D02*
X595932D01*
X598656Y30307D01*
G01X589104Y43217D02*
X593347D01*
G01D02*
X596057D01*
X596823Y43983D01*
X599948D01*
G01X630095Y42707D02*
X630273D01*
G01X636647Y56857D02*
Y55353D01*
X637347Y54653D01*
Y44607D01*
X635447Y42707D01*
X630273D01*
G01X598513Y57106D02*
X603051Y52568D01*
Y51073D01*
G01X598513Y57106D02*
X594615D01*
X594504Y57217D01*
G01X593247Y47907D02*
X594547D01*
X596503Y45951D01*
X599948D01*
G01X585104Y45967D02*
Y41717D01*
X585354Y41467D01*
G01X585104Y45967D02*
X587044Y47907D01*
X593247D01*
G01X582754Y40567D02*
X581854Y41467D01*
G01X582797Y31807D02*
Y37207D01*
G01X600847Y33907D02*
Y34903D01*
X603051Y37107D01*
Y38861D01*
G01X582754Y40567D02*
Y37250D01*
X582797Y37207D01*
G01X594541Y29531D02*
Y25888D01*
X593563Y24910D01*
G01D02*
X592733Y24080D01*
X588753D01*
G01X604047Y57707D02*
Y61607D01*
X603747Y61907D01*
G01X598947Y63207D02*
X602447D01*
X603747Y61907D01*
G01X604047Y57707D02*
Y56053D01*
X605020Y55080D01*
Y51023D01*
G01X646199Y42707D02*
X646021D01*
G01X714454Y422965D02*
X712135D01*
X711300Y423800D01*
G01X713189Y531004D02*
Y524511D01*
G01X707283Y531004D02*
Y524511D01*
G01X701378Y531004D02*
Y524511D01*
G01X695472Y531004D02*
Y524511D01*
G01X689567Y531004D02*
Y524511D01*
G01X683661Y531004D02*
Y524511D01*
G01X677756Y531004D02*
Y524511D01*
G01X671850Y531004D02*
Y524511D01*
G01X781200Y29800D02*
Y34800D01*
X778800Y37200D01*
X774200D01*
G01D02*
X772100D01*
X770040Y35140D01*
Y31535D01*
G01X781100Y25000D02*
Y19400D01*
G01D02*
X776060D01*
X775160Y20300D01*
Y23465D01*
G01X722134Y406785D02*
X724453D01*
X725288Y405950D01*
G01X742716Y531004D02*
Y536435D01*
G01X738779Y531004D02*
Y536435D01*
G01X782086Y531004D02*
Y536435D01*
G01X776181Y531004D02*
Y536435D01*
G01X770275Y531004D02*
Y536435D01*
G01X725000Y531004D02*
Y536435D01*
G01X719094Y531004D02*
Y536005D01*
X719394Y536305D01*
G01X787200Y29800D02*
X795633D01*
X801024Y24409D01*
G01X821024D02*
X816415Y19800D01*
X797000D01*
X791800Y25000D01*
X787100D01*
G01X852682Y74813D02*
X844300Y83195D01*
Y131850D01*
X830450Y145700D01*
Y169555D01*
X832572Y171677D01*
G01X904262Y69540D02*
Y60126D01*
X899105Y54969D01*
X872526D01*
X852682Y74813D01*
G01X854422Y145014D02*
X856722D01*
X857722Y146014D01*
X881022D01*
X882622Y144414D01*
Y129353D01*
G01X850061Y165178D02*
Y164253D01*
X846122Y160314D01*
G01X858373Y174835D02*
X861748Y178210D01*
Y181622D01*
G01X850061Y169478D02*
Y165178D01*
G01Y169478D02*
X853016D01*
X858373Y174835D01*
G01X846077Y155674D02*
Y160269D01*
X846122Y160314D01*
G01X854672Y149514D02*
X856622D01*
X857822Y148314D01*
X880722D01*
X882622Y150214D01*
Y164275D01*
G01X848422Y145014D02*
Y146764D01*
X851172Y149514D01*
G01X849625Y177727D02*
Y174747D01*
X848077Y173199D01*
X842614D01*
X836450Y167035D01*
Y148701D01*
X840137Y145014D01*
X842508D01*
G01D02*
X848422D01*
G01X852418Y203864D02*
X853268D01*
X854868Y202264D01*
X856568D01*
X857924Y200908D01*
X859779D01*
G01X852418Y203864D02*
Y201145D01*
X851137Y199864D01*
G01X856268Y207064D02*
X858768Y204564D01*
X860338D01*
X861748Y203154D01*
Y200908D01*
G01X859779Y181622D02*
X853769D01*
X853750Y181603D01*
G01D02*
X850001D01*
X849625Y181227D01*
G01X841625D02*
Y184621D01*
X842168Y185164D01*
G01X845625Y181127D02*
X841725D01*
X841625Y181227D01*
G01X845625Y181127D02*
X849525D01*
X849625Y181227D01*
G01X841625Y177727D02*
X841608Y177710D01*
X837195D01*
G01D02*
X832605D01*
X832572Y177677D01*
G01X845625Y177627D02*
X841725D01*
X841625Y177727D01*
G01X854634Y166390D02*
X854596Y166352D01*
G01X858622Y162564D02*
X854617D01*
X854596Y162585D01*
G01X863716Y181622D02*
Y177712D01*
X862342Y176338D01*
Y174098D01*
X854634Y166390D01*
G01X854596Y166352D02*
Y162585D01*
G01X852418Y211864D02*
Y215964D01*
G01X856196Y212359D02*
Y210836D01*
X859418Y207614D01*
X860118D01*
X863716Y204016D01*
Y200908D01*
G01X852418Y215964D02*
X854896D01*
X856196Y214664D01*
Y212359D01*
G01X857700Y222300D02*
X862532D01*
X867080Y217752D01*
Y215262D01*
G01X856468Y207064D02*
X856268D01*
G01D02*
X855468Y207864D01*
X852418D01*
G01X848918Y215964D02*
Y219014D01*
X848868Y219064D01*
G01X877456Y322390D02*
Y339640D01*
X875856Y341240D01*
X851506D01*
X850506Y340240D01*
G01X849506Y344740D02*
X850506Y343740D01*
X875756D01*
X877456Y345440D01*
Y357012D01*
G01X844506Y340240D02*
X842202Y337936D01*
X838169D01*
G01X846006Y344740D02*
X844506Y343240D01*
Y340240D01*
G01X838169Y337936D02*
X832694D01*
X826369Y344261D01*
Y362460D01*
X828928Y365019D01*
X837471D01*
X842984Y370532D01*
Y371019D01*
G01X805034Y405785D02*
X807353D01*
X808188Y404950D01*
G01X797354Y421965D02*
X795035D01*
X794200Y422800D01*
G01X820568Y371019D02*
X817000D01*
X816997Y371022D01*
G01X851820Y366572D02*
X853418D01*
X858240Y371394D01*
Y373756D01*
G01X839663Y360311D02*
Y356034D01*
X839689Y356008D01*
G01X845111Y362071D02*
X847319D01*
X851820Y366572D01*
G01X845111Y362071D02*
X843873D01*
X842113Y360311D01*
X839663D01*
G01X857706Y399786D02*
X858320Y399172D01*
Y397733D01*
X860208Y395845D01*
Y393042D01*
G01X853060Y404248D02*
X853244D01*
X857706Y399786D01*
G01X848910Y403998D02*
X849160Y404248D01*
X853060D01*
G01X848910Y395998D02*
X850510Y394398D01*
X853060D01*
X854416Y393042D01*
X856271D01*
G01X848910Y395998D02*
Y393279D01*
X847629Y391998D01*
G01X852716Y399376D02*
X852094Y399998D01*
X848910D01*
G01X858240Y393042D02*
Y395313D01*
X856484Y397069D01*
X855023D01*
X852716Y399376D01*
G01X838972Y374519D02*
X834984D01*
G01X842984D02*
X838972D01*
G01X847820Y375672D02*
X849504D01*
X851420Y373756D01*
X856271D01*
G01X842984Y374519D02*
X844137Y375672D01*
X847820D01*
G01X834984Y374519D02*
Y375122D01*
X838627Y378765D01*
G01X855320Y414472D02*
X856420D01*
X863320Y407572D01*
Y405672D01*
G01X846456Y354007D02*
Y350814D01*
G01X836189Y356008D02*
X836166Y355985D01*
Y351914D01*
G01D02*
X834601D01*
X832585Y353930D01*
X830133D01*
G01X830809Y371019D02*
X826568D01*
G01X838972D02*
X834984D01*
G01D02*
X830809D01*
G01X817519Y531004D02*
Y536435D01*
G01X811614Y531004D02*
Y536435D01*
G01X805708Y531004D02*
Y536435D01*
G01X841141Y531004D02*
Y536435D01*
G01X837204Y531004D02*
Y536435D01*
G01X799803Y531004D02*
Y536435D01*
G01X793897Y531004D02*
Y536435D01*
G01X787992Y531004D02*
Y536435D01*
G01X823425Y531004D02*
Y534625D01*
X825000Y536200D01*
G01X867653Y181622D02*
Y172764D01*
G01X858622Y159064D02*
Y155614D01*
G01X866968Y210564D02*
Y208239D01*
X867653Y207554D01*
Y200908D01*
G01X864992Y175435D02*
X865685Y176128D01*
Y181622D01*
G01Y200908D02*
Y205195D01*
X865153Y205727D01*
Y205774D01*
X864492Y206435D01*
G01X860868Y219764D02*
X863580Y217052D01*
Y215262D01*
G01X867080D02*
X866968Y215150D01*
Y210564D01*
G01X864145Y373756D02*
Y369747D01*
X864920Y368972D01*
G01X862177Y368262D02*
Y373756D01*
G01X863320Y405672D02*
Y402297D01*
X864145Y401472D01*
Y393042D01*
G01X862177D02*
Y398376D01*
X861484Y399069D01*
X34652Y111485D03*
X33297Y703990D03*
X89764Y238386D03*
X90157Y413582D03*
X148206Y21054D03*
X201801Y684252D03*
X261147Y405580D03*
X225601Y684252D03*
X309055Y157677D03*
X305906Y182874D03*
Y388386D03*
X309252Y413583D03*
X488838Y137225D03*
Y164744D03*
X486498Y356293D03*
X706299Y83661D03*
Y201771D03*
X666929Y510236D03*
X765354D03*
X745669D03*
X804724Y83661D03*
Y201772D03*
X844094Y510236D03*
X807831Y734367D03*
X899219Y47960D03*
G54D134*
G01X88325Y556542D02*
Y556540D01*
X86750Y554965D01*
G01X85175Y556542D02*
X85177D01*
X86750Y558115D01*
G01X154724Y569291D02*
G03X153400Y570125I-1324J-634D01*
G01X149416D01*
G02X144749Y572057I-1J6600D01*
G01X144589Y572217D01*
G03X142186Y573213I-2404J-2403D01*
G01X136575D01*
G02X131908Y575145I-1J6600D01*
G01X131026Y576027D01*
G03X128623Y577023I-2404J-2403D01*
G01X116737D01*
G03X114836Y575122I0J-1901D01*
G03X116738Y573220I1902J0D01*
G01X126947D01*
G02X128428Y572605I0J-2091D01*
G01X128451Y572582D01*
G02X129090Y571042I-1539J-1541D01*
G01Y570969D01*
G03X130607Y569636I1344J0D01*
G01X154724Y572441D02*
G02X153400Y571725I-1324J866D01*
G01X149416D01*
G02X145881Y573189I0J5000D01*
G01X145721Y573349D01*
G03X142186Y574813I-3535J-3536D01*
G01X136575D01*
G02X133040Y576277I0J5000D01*
G01X132158Y577159D01*
G03X128623Y578623I-3535J-3536D01*
G01X116737D01*
G03X113236Y575122I0J-3501D01*
G03X116738Y571620I3502J0D01*
G01X126947D01*
G02X127294Y571475I-1J-490D01*
G01X127319Y571450D01*
X127320D01*
G02X127490Y571041I-408J-410D01*
G01Y570699D01*
G02X126347Y569556I-1143J0D01*
G01X72577Y569140D02*
X74152Y567565D01*
G01X86750Y586463D02*
X85175Y584888D01*
G01X72577Y565990D02*
X71002Y567565D01*
G01X86750Y583313D02*
X85175Y581738D01*
G01X154724Y575590D02*
G03X153631Y576530I-1093J-165D01*
G01X149963D01*
G03X148409Y575672I0J-1836D01*
G01X144876Y590854D02*
X145540Y590191D01*
G03X146724Y589700I1185J1184D01*
G01X147750D01*
G02X150396Y588604I0J-3742D01*
G01X151182Y587818D01*
G03X152399Y587314I1217J1217D01*
G01X153368D01*
G03X154189Y587654I0J1161D01*
G01X154724Y588189D01*
G01X148409Y579353D02*
G03X149864Y578130I1455J254D01*
G01X153632D01*
G03X153756Y578136I0J1282D01*
G03X154724Y578740I-124J1276D01*
G01X144876Y587173D02*
X145152Y587449D01*
G02X146724Y588100I1572J-1572D01*
G01X147750D01*
G02X149264Y587472I-1J-2142D01*
G01X150050Y586686D01*
Y586687D01*
G03X152400Y585714I2349J2348D01*
G01X153368D01*
G02X154530Y585232I-1J-1644D01*
G01X154724Y585039D01*
G54D50*
X135019Y714845D03*
G54D14*
X34000Y54300D03*
X73768Y64555D03*
X93614Y507152D03*
X73427Y695585D03*
X127300Y643300D03*
X115619Y712795D03*
X283032Y736236D03*
X345034Y128412D03*
X294018Y665582D03*
X352180Y642014D03*
X539108Y74841D03*
X577404Y60567D03*
X641347Y63007D03*
X598947Y69007D03*
X603747Y67707D03*
X832572Y177477D03*
G54D32*
X61284Y643900D03*
X44684Y671800D03*
X208150Y634100D03*
X206900Y630600D03*
X145100Y691600D03*
X143817Y740048D03*
X283400Y531100D03*
X282570Y644150D03*
X272020Y715620D03*
X302070Y612350D03*
X318700Y599000D03*
X284895Y576463D03*
X291204Y688120D03*
X370504Y197291D03*
X358986Y639880D03*
X442535Y34357D03*
X704100Y423800D03*
X787000Y422800D03*
G54D23*
X70865Y98425D03*
Y472441D03*
X49212Y740157D03*
X314960Y472441D03*
X364173Y740157D03*
X405511Y39370D03*
X587795Y307087D03*
X590551Y472441D03*
X612204Y606299D03*
X875984Y31496D03*
Y472441D03*
Y606299D03*
Y740157D03*
G54D125*
X862772Y111138D03*
X887572D03*
X862772Y90638D03*
X887572D03*
X898101Y283208D03*
X873301D03*
X898101Y303708D03*
X873301D03*
G54D107*
X545658Y31633D03*
G54D41*
X119300Y518400D03*
X136000Y628900D03*
X81784Y671500D03*
X85400Y638516D03*
X188500Y693600D03*
X171747Y708475D03*
X258823Y628146D03*
X263000Y679300D03*
X243731Y705874D03*
X218623Y655646D03*
X225400Y716600D03*
X317600Y610400D03*
X322000Y645600D03*
X314720Y681820D03*
X311704Y715720D03*
X369400Y119500D03*
X523301Y54449D03*
X622537Y34526D03*
X589104Y43267D03*
X586647Y60807D03*
X669447Y37707D03*
X845625Y181177D03*
X838972Y374569D03*
G54D116*
X665551Y527953D03*
X763976D03*
X747047D03*
X845472D03*
G54D135*
G01X220866Y581890D02*
Y581891D01*
X221812Y582837D01*
X226822D01*
X239760Y595775D01*
X248675D01*
X253188Y600288D01*
X256227D01*
X257346Y599169D01*
G01X220866Y585039D02*
X221843Y584062D01*
X226314D01*
X239252Y597000D01*
X248167D01*
X252680Y601513D01*
X256276D01*
X257332Y602569D01*
G01X258398Y605915D02*
X257151Y607162D01*
X253609D01*
X253171Y606724D01*
X239057D01*
X236425Y604092D01*
Y600252D01*
X231617Y595444D01*
X229352D01*
X222583Y588675D01*
X221352D01*
X220866Y588189D01*
G01X258398Y609484D02*
X257301Y608387D01*
X253101D01*
X252663Y607949D01*
X238549D01*
X235200Y604600D01*
Y600760D01*
X231109Y596669D01*
X228844D01*
X222075Y589900D01*
X219427D01*
X217716Y588189D01*
G01X372000Y68550D02*
X371142Y67692D01*
X365930D01*
X365291Y68331D01*
X363555D01*
X362905Y67681D01*
X361180D01*
X360530Y68331D01*
X358805D01*
X358155Y67681D01*
X351867D01*
X348646Y70902D01*
X347299D01*
X346457Y71744D01*
Y74724D01*
G01X372000Y65650D02*
X371194Y66456D01*
X351359D01*
X348138Y69677D01*
X347292D01*
X346457Y68842D01*
Y66850D01*
G01X297146Y277756D02*
X301487D01*
X302461Y278730D01*
X304821D01*
X304822Y278729D01*
G02X307567Y277592I0J-3882D01*
G01X304548Y268508D02*
G02X302751Y267371I-1797J852D01*
G01X301758D01*
X300822Y268307D01*
X297146D01*
G01Y265158D02*
X300863D01*
X301851Y266146D01*
X302751D01*
G02X304548Y265008I0J-1988D01*
G01X297146Y280906D02*
X301583D01*
X302534Y279955D01*
X304822D01*
G03X307567Y281092I0J3882D01*
G01X297146Y293504D02*
X300528D01*
X301477Y292555D01*
X302470D01*
G03X304267Y293692I0J1989D01*
G01X297146Y290354D02*
X300594D01*
X301570Y291330D01*
X302470D01*
G02X304267Y290192I0J-1988D01*
G01X297146Y306102D02*
X301587D01*
X302534Y305155D01*
X304822D01*
G03X307567Y306292I0J3882D01*
G01X297146Y302953D02*
X301484D01*
X302461Y303930D01*
X304821D01*
X304822Y303929D01*
G02X307567Y302792I0J-3882D01*
G01X297146Y318701D02*
X300531D01*
X301477Y317755D01*
X302470D01*
G03X304267Y318892I0J1989D01*
G01X297146Y315551D02*
X300591D01*
X301570Y316530D01*
X302470D01*
G02X304267Y315392I0J-1988D01*
G01X297146Y331299D02*
X301590D01*
X302534Y330355D01*
X304822D01*
G03X307567Y331492I0J3882D01*
G01X297146Y328150D02*
X301481D01*
X302461Y329130D01*
X304821D01*
X304822Y329129D01*
G02X307567Y327992I0J-3882D01*
G01X297146Y343898D02*
X300534D01*
X301477Y342955D01*
X302470D01*
G03X304267Y344092I0J1989D01*
G01X297146Y340748D02*
X300588D01*
X301570Y341730D01*
X302470D01*
G02X304267Y340592I0J-1988D01*
G01X314666Y287205D02*
X318710D01*
X319698Y286217D01*
X331362D01*
G03X334107Y287354I0J3882D01*
G01X314666Y284055D02*
X318757D01*
X319694Y284992D01*
X331361D01*
X331362Y284991D01*
G02X334107Y283854I0J-3882D01*
G01X314666Y299803D02*
X319177D01*
X320140Y298840D01*
X325437D01*
G03X328182Y299977I0J3882D01*
G01X314666Y296654D02*
X319074D01*
X320035Y297615D01*
X325436D01*
X325437Y297614D01*
G02X328182Y296477I0J-3882D01*
G01X314666Y312402D02*
X319229D01*
X320184Y311447D01*
X331848D01*
G03X334593Y312584I0J3882D01*
G01X314666Y309252D02*
X319210D01*
X320180Y310222D01*
X331847D01*
X331848Y310221D01*
G02X334593Y309084I0J-3882D01*
G01X314666Y325000D02*
X319127D01*
X320140Y323987D01*
X325437D01*
G03X328182Y325124I0J3882D01*
G01X314666Y321850D02*
X319123D01*
X320035Y322762D01*
X325436D01*
X325437Y322761D01*
G02X328182Y321624I0J-3882D01*
G01X314666Y337599D02*
X319158D01*
X320173Y336584D01*
X331837D01*
G03X334582Y337721I0J3882D01*
G01X314666Y334449D02*
X319259D01*
X320169Y335359D01*
X331836D01*
X331837Y335358D01*
G02X334582Y334221I0J-3882D01*
G01X314666Y350197D02*
X319127D01*
X320145Y349179D01*
X325442D01*
G03X328187Y350316I0J3882D01*
G01X314666Y347047D02*
X319133D01*
X320040Y347954D01*
X325441D01*
X325442Y347953D01*
G02X328187Y346816I0J-3882D01*
G01X297146Y356496D02*
X301593D01*
X302534Y355555D01*
X304822D01*
G03X307567Y356692I0J3882D01*
G01X297146Y353347D02*
X301478D01*
X302461Y354330D01*
X304821D01*
X304822Y354329D01*
G02X307567Y353192I0J-3882D01*
G01X297146Y369095D02*
X300537D01*
X301477Y368155D01*
X302470D01*
G03X304267Y369292I0J1989D01*
G01X297146Y365945D02*
X300585D01*
X301570Y366930D01*
X302470D01*
G02X304267Y365792I0J-1988D01*
G01X314666Y362795D02*
X319215D01*
X320173Y361837D01*
X331837D01*
G03X334582Y362974I0J3882D01*
G01X314666Y359646D02*
X319203D01*
X320169Y360612D01*
X331836D01*
X331837Y360611D01*
G02X334582Y359474I0J-3882D01*
G01X314666Y375394D02*
X319127D01*
X320140Y374381D01*
X325437D01*
G03X328182Y375518I0J3882D01*
G01X314666Y372244D02*
X319123D01*
X320035Y373156D01*
X325436D01*
X325437Y373155D01*
G02X328182Y372018I0J-3882D01*
G01X341755Y627231D02*
X342917Y626069D01*
X344197D01*
X346771Y623495D01*
Y622354D01*
X349038Y620087D01*
X349687D01*
X350094Y620494D01*
X353514D01*
G01X353864Y618526D02*
X350074D01*
X349738Y618862D01*
X348530D01*
X345546Y621846D01*
Y622987D01*
X343689Y624844D01*
X342917D01*
X341755Y623682D01*
G01X341600Y616962D02*
X342719Y615843D01*
X346817D01*
X347210Y616236D01*
X350179D01*
X350500Y616557D01*
X353864D01*
G01X341600Y613413D02*
X342805Y614618D01*
X347325D01*
X347718Y615011D01*
X350318D01*
X350740Y614589D01*
X353864D01*
G01X334264Y602648D02*
X335426Y603810D01*
Y606171D01*
X337134Y607879D01*
X343655D01*
X346041Y610265D01*
X350212D01*
X350598Y610651D01*
X353864D01*
G01X337813Y602648D02*
X336651Y603810D01*
Y605663D01*
X337642Y606654D01*
X344163D01*
X346549Y609040D01*
X350238D01*
X350598Y608683D01*
X353864D01*
G01X372000Y68550D02*
X372836Y67714D01*
X380264D01*
X385224Y62754D01*
X387477D01*
X388798Y64075D01*
Y65134D01*
X387558Y66374D01*
Y69149D01*
G01X372000Y65650D02*
X372839Y66489D01*
X379756D01*
X384716Y61529D01*
X387985D01*
X390023Y63567D01*
Y65301D01*
X391358Y66636D01*
Y69149D01*
G01X387558Y75749D02*
Y78398D01*
X388995Y79835D01*
Y81768D01*
X387833Y82930D01*
G01X391358Y75749D02*
Y78402D01*
X390220Y79540D01*
Y81768D01*
X391382Y82930D01*
G01X400924Y155896D02*
X401940Y154880D01*
Y106710D01*
X410507Y98143D01*
X423325D01*
X431295Y90173D01*
X463092D01*
X466925Y94006D01*
Y102009D01*
X461908Y107026D01*
X457407D01*
X452425Y112008D01*
Y116324D01*
X454155Y118054D01*
Y174909D01*
X452466Y176598D01*
X450575D01*
X450000Y177173D01*
Y178740D01*
G01X404473Y155896D02*
X403165Y154588D01*
Y107218D01*
X411015Y99368D01*
X423833D01*
X431803Y91398D01*
X439274D01*
X439874Y91998D01*
X441599D01*
X442199Y91398D01*
X443924D01*
X444524Y91998D01*
X446249D01*
X446849Y91398D01*
X448574D01*
X449174Y91998D01*
X450899D01*
X451499Y91398D01*
X462584D01*
X465700Y94514D01*
Y101501D01*
X461400Y105801D01*
X456899D01*
X451200Y111500D01*
Y116832D01*
X452930Y118562D01*
Y174401D01*
X451958Y175373D01*
X450575D01*
X450000Y174798D01*
Y173229D01*
G01X388338Y643600D02*
X387269Y644669D01*
X383469D01*
X368668Y629868D01*
Y627619D01*
X369101Y627186D01*
Y623920D01*
G01X388338Y647149D02*
X387083Y645894D01*
X382961D01*
X367443Y630376D01*
Y627496D01*
X367133Y627186D01*
Y623920D01*
G01X527953Y174016D02*
Y172516D01*
G03X528596Y171873I643J0D01*
G01X529788D01*
G02X532107Y169554I0J-2319D01*
G01Y120244D01*
X529657Y117793D01*
X512965Y106949D01*
X509797D01*
X508493Y105645D01*
Y104497D01*
G03X509796Y103194I1303J0D01*
G01X509981D01*
G01X527953Y168504D02*
Y170004D01*
G02X528597Y170648I644J0D01*
G01X529788D01*
G02X530882Y169554I0J-1094D01*
G01Y120752D01*
X530881D01*
X530380Y120251D01*
X528881Y118751D01*
X512602Y108174D01*
X509289D01*
X507268Y106153D01*
Y104497D01*
G02X505965Y103194I-1303J0D01*
G01X505779D01*
G01X708682Y551846D02*
X709035Y552199D01*
G02X709937I451J-451D01*
G01X710781Y551355D01*
G02Y548859I-1248J-1248D01*
G01X703691Y541769D01*
Y534675D01*
X703346Y534330D01*
Y531004D01*
G01X711156Y554320D02*
X710803Y553967D01*
G03Y553067I450J-450D01*
G01X711648Y552222D01*
G02Y547992I-2115J-2115D01*
G01X710134Y546478D01*
X710133D01*
X704916Y541261D01*
Y534700D01*
X705324Y534292D01*
Y531013D01*
X705315Y531004D01*
G01X686198Y552098D02*
X686551Y552451D01*
G02X687453I451J-451D01*
G01Y552452D01*
X688056Y551848D01*
X688057D01*
G03X690008Y551040I1952J1953D01*
G01X691310D01*
G02X692562Y549788I0J-1252D01*
G01Y538035D01*
X691907Y537380D01*
Y534702D01*
X691535Y534330D01*
Y531004D01*
G01X688672Y554572D02*
X688319Y554219D01*
G03Y553319I450J-450D01*
G01X688923Y552715D01*
G03X690009Y552265I1086J1086D01*
G01X691310D01*
G02X693787Y549788I0J-2477D01*
G01Y537527D01*
X693132Y536872D01*
Y534673D01*
X693504Y534301D01*
Y531004D01*
G01X671024Y544571D02*
X671377Y544924D01*
G02X672279I451J-451D01*
G01X680069Y537134D01*
Y534675D01*
X679724Y534330D01*
Y531004D01*
G01X673498Y547045D02*
X673145Y546692D01*
G03Y545792I450J-450D01*
G01X681294Y537643D01*
Y534700D01*
X681702Y534292D01*
Y531013D01*
X681693Y531004D01*
G01X717829Y549856D02*
X718182Y550209D01*
G02X719084I451J-451D01*
G01X720094Y549198D01*
G02Y547892I-653J-653D01*
G01X716931Y544729D01*
X714356D01*
X709597Y539970D01*
Y534675D01*
X709252Y534330D01*
Y531004D01*
G01X720303Y552330D02*
X719950Y551977D01*
G03Y551077I450J-450D01*
G01X719951Y551076D01*
Y551075D01*
X720642Y550384D01*
X720961Y550064D01*
G02Y547025I-1520J-1520D01*
G01X717440Y543504D01*
X714864D01*
X710822Y539462D01*
Y534700D01*
X711220Y534302D01*
Y531004D01*
G01X699453Y551078D02*
X699806Y551431D01*
G02X700708I451J-451D01*
G01X701518Y550621D01*
G02Y548041I-1290J-1290D01*
G01X697786Y544309D01*
Y534675D01*
X697441Y534330D01*
Y531004D01*
G01X701927Y553552D02*
X701574Y553199D01*
G03Y552299I450J-450D01*
G01X702385Y551488D01*
G02Y547174I-2157J-2157D01*
G01X701243Y546032D01*
X701242D01*
X699011Y543801D01*
Y534700D01*
X699409Y534302D01*
Y531004D01*
G01X684818Y543012D02*
X685171Y543365D01*
G02X686073I451J-451D01*
G01X687187Y542251D01*
Y539732D01*
X685975Y538520D01*
Y534675D01*
X685630Y534330D01*
Y531004D01*
G01X687292Y545486D02*
X686939Y545133D01*
G03Y544233I450J-450D01*
G01X688412Y542760D01*
Y539224D01*
X687200Y538012D01*
Y534700D01*
X687598Y534302D01*
Y531004D01*
G01X657921Y539000D02*
X658274Y539353D01*
G02X659176I451J-451D01*
G01X659660Y538869D01*
Y538870D01*
G03X661523Y538099I1861J1861D01*
G01X671431D01*
X674164Y535366D01*
Y534675D01*
X673819Y534330D01*
Y531004D01*
G01X660395Y541474D02*
X660042Y541121D01*
G03Y540221I450J-450D01*
G01X660527Y539736D01*
G03X661522Y539324I995J995D01*
G01X671939D01*
X675389Y535874D01*
Y534700D01*
X675787Y534302D01*
Y531004D01*
G01X768263Y552763D02*
X768616Y553116D01*
G02X769518I451J-451D01*
G01Y553117D01*
X770518Y552116D01*
Y552117D01*
G02X771027Y550889I-1226J-1228D01*
G01Y545872D01*
X773417Y543482D01*
X778494Y538406D01*
Y534675D01*
X778149Y534330D01*
Y531004D01*
G01X770737Y555237D02*
X770384Y554884D01*
G03Y553984I450J-450D01*
G01X771385Y552983D01*
G02X772252Y550890I-2093J-2093D01*
G01Y546380D01*
X774284Y544348D01*
X779719Y538914D01*
Y534700D01*
X780127Y534292D01*
Y531013D01*
X780118Y531004D01*
G01X728682Y549946D02*
X729035Y550299D01*
G02X729937I451J-451D01*
G01X730781Y549455D01*
G02Y547361I-1047J-1047D01*
G01X723204Y539784D01*
X718676D01*
X715502Y536610D01*
Y534675D01*
X715157Y534330D01*
Y531004D01*
G01X731156Y552420D02*
X730803Y552067D01*
G03Y551167I450J-450D01*
G01X731648Y550322D01*
G02Y546494I-1914J-1914D01*
G01X730637Y545483D01*
X730636D01*
X723712Y538559D01*
X719184D01*
X716727Y536102D01*
Y534700D01*
X717126Y534301D01*
Y531004D01*
G01X720536Y523519D02*
X721036D01*
G03X721672Y524155I0J636D01*
G01Y525355D01*
X721435Y525592D01*
Y527114D01*
X721063Y527486D01*
Y531004D01*
G01X724036Y523519D02*
X723536D01*
G02X722898Y524157I0J638D01*
G01X722897Y524158D01*
Y525863D01*
X722660Y526100D01*
Y527114D01*
X723031Y527485D01*
Y531004D01*
G01X778763Y553763D02*
X779116Y554116D01*
G02X780018I451J-451D01*
G01Y554117D01*
X780855Y553279D01*
Y553280D01*
G02X781033Y552851I-427J-429D01*
G01Y543834D01*
X784400Y540467D01*
Y534675D01*
X784055Y534330D01*
Y531004D01*
G01X781237Y556237D02*
X780884Y555884D01*
G03Y554984I450J-450D01*
G01X781722Y554146D01*
G02X782258Y552852I-1294J-1294D01*
G01Y544342D01*
X785625Y540975D01*
Y534700D01*
X786023Y534302D01*
Y531004D01*
G01X756263Y548263D02*
X756616Y548616D01*
G02X757518I451J-451D01*
G01Y548617D01*
X764960Y541175D01*
X768426D01*
X772589Y537012D01*
Y534675D01*
X772244Y534330D01*
Y531004D01*
G01X758737Y550737D02*
X758384Y550384D01*
G03Y549484I450J-450D01*
G01X765468Y542400D01*
X768934D01*
X773814Y537520D01*
Y534700D01*
X774212Y534302D01*
Y531004D01*
G01X788263Y554763D02*
X788616Y555116D01*
G02X789518I451J-451D01*
G01X790317Y554317D01*
G02Y551971I-1173J-1173D01*
G01X789275Y550929D01*
Y543992D01*
X790305Y542962D01*
Y534675D01*
X789960Y534330D01*
Y531004D01*
G01X790737Y557237D02*
X790384Y556884D01*
G03Y555984I450J-450D01*
G01X791184Y555184D01*
G02Y551104I-2040J-2040D01*
G01X790500Y550420D01*
Y544500D01*
X791530Y543470D01*
Y534700D01*
X791938Y534292D01*
Y531013D01*
X791929Y531004D01*
G01X825263Y553263D02*
X825616Y553616D01*
G02X826518I451J-451D01*
G01X827365Y552769D01*
G02Y550097I-1336J-1336D01*
G01X824743Y547475D01*
X823895D01*
X813927Y537508D01*
Y534675D01*
X813582Y534330D01*
Y531004D01*
G01X827737Y555737D02*
X827384Y555384D01*
G03Y554484I450J-450D01*
G01X828232Y553636D01*
G02Y549230I-2203J-2203D01*
G01X825252Y546250D01*
X824403D01*
X815152Y537000D01*
Y534700D01*
X815560Y534292D01*
Y531013D01*
X815551Y531004D01*
G01X806763Y554763D02*
X807116Y555116D01*
G02X808018I451J-451D01*
G01X808752Y554382D01*
G02Y551824I-1279J-1279D01*
G01X802116Y545188D01*
Y534675D01*
X801771Y534330D01*
Y531004D01*
G01X809237Y557237D02*
X808884Y556884D01*
G03Y555984I450J-450D01*
G01X809619Y555249D01*
G02Y550957I-2146J-2146D01*
G01X803341Y544679D01*
Y534700D01*
X803740Y534301D01*
Y531004D01*
G01X842369Y549234D02*
X842016Y548881D01*
G02X841114I-451J451D01*
G01X840267Y549728D01*
G03X834927I-2670J-2670D01*
G01X833043Y547844D01*
Y547843D01*
X825700Y540500D01*
X824177D01*
X819859Y536182D01*
Y534951D01*
X819488Y534580D01*
Y531004D01*
G01X839895Y546760D02*
X840248Y547113D01*
G03Y548013I-450J450D01*
G01X839400Y548861D01*
G03X835794I-1803J-1803D01*
G01X826208Y539275D01*
X824685D01*
X821084Y535674D01*
Y534833D01*
X821456Y534461D01*
Y531004D01*
G01X812763Y548263D02*
X813116Y548616D01*
G02X814018I451J-451D01*
G01Y548617D01*
X815144Y547492D01*
G02Y545940I-776J-776D01*
G01X808022Y538820D01*
Y534675D01*
X807677Y534330D01*
Y531004D01*
G01X815237Y550737D02*
X814884Y550384D01*
G03Y549485I450J-450D01*
G01X815242Y549127D01*
X816011Y548359D01*
G02Y545073I-1643J-1643D01*
G01X809415Y538480D01*
G03X809411Y538475I444J-359D01*
G01X809247Y538312D01*
Y534700D01*
X809645Y534302D01*
Y531004D01*
G01X797763Y554263D02*
X798116Y554616D01*
G02X799018I451J-451D01*
G01X799703Y553931D01*
G02X800066Y553055I-876J-876D01*
G01Y551066D01*
X796211Y547211D01*
Y534675D01*
X795866Y534330D01*
Y531004D01*
G01X800237Y556737D02*
X799884Y556384D01*
G03Y555484I450J-450D01*
G01X800570Y554798D01*
Y554797D01*
G02X801291Y553056I-1743J-1742D01*
G01Y550558D01*
X797436Y546703D01*
Y534700D01*
X797834Y534302D01*
Y531004D01*
G54D24*
X37500Y157500D03*
X75000D03*
G54D33*
X65714Y665850D03*
X306300Y638600D03*
X295634Y710070D03*
G54D60*
X163189Y669291D03*
G54D126*
X882622Y129353D03*
Y164275D03*
G54D51*
X125376Y705002D03*
Y706971D03*
Y708939D03*
Y710908D03*
Y712876D03*
Y714845D03*
Y716814D03*
Y718782D03*
Y720751D03*
Y722719D03*
Y724688D03*
X144662Y708939D03*
Y706971D03*
Y705002D03*
Y724688D03*
Y722719D03*
Y720751D03*
Y718782D03*
Y716814D03*
Y714845D03*
Y712876D03*
Y710908D03*
G54D117*
X714173Y501279D03*
X712205D03*
X710236D03*
X708268D03*
X706299D03*
X704330D03*
X702362D03*
X700393D03*
X698425D03*
X696456D03*
X694488D03*
X692519D03*
X690551D03*
X688582D03*
X686614D03*
X684645D03*
X682677D03*
X680708D03*
X678740D03*
X676771D03*
X674803D03*
X672834D03*
X670866D03*
X713189Y531004D03*
X711220D03*
X709252D03*
X707283D03*
X705315D03*
X703346D03*
X701378D03*
X699409D03*
X697441D03*
X695472D03*
X693504D03*
X691535D03*
X689567D03*
X687598D03*
X685630D03*
X683661D03*
X681693D03*
X679724D03*
X677756D03*
X675787D03*
X673819D03*
X671850D03*
X669882D03*
X785039Y501279D03*
X783070D03*
X781102D03*
X779133D03*
X777165D03*
X775196D03*
X773228D03*
X771259D03*
X769291D03*
X786023Y531004D03*
X784055D03*
X782086D03*
X780118D03*
X778149D03*
X776181D03*
X774212D03*
X772244D03*
X770275D03*
X768307D03*
X741732Y501279D03*
X739764D03*
X737795D03*
X735827D03*
X725984D03*
X724016D03*
X722047D03*
X720079D03*
X718110D03*
X716142D03*
X742716Y531004D03*
X740748D03*
X738779D03*
X736811D03*
X734842D03*
X725000D03*
X723031D03*
X721063D03*
X719094D03*
X717126D03*
X715157D03*
X840157Y501279D03*
X838189D03*
X836220D03*
X834252D03*
X824409D03*
X822441D03*
X820472D03*
X818504D03*
X816535D03*
X814567D03*
X812598D03*
X810630D03*
X808661D03*
X806693D03*
X804724D03*
X802755D03*
X800787D03*
X798818D03*
X796850D03*
X794881D03*
X792913D03*
X790944D03*
X788976D03*
X787007D03*
X841141Y531004D03*
X839173D03*
X837204D03*
X835236D03*
X833267D03*
X823425D03*
X821456D03*
X819488D03*
X817519D03*
X815551D03*
X813582D03*
X811614D03*
X809645D03*
X807677D03*
X805708D03*
X803740D03*
X801771D03*
X799803D03*
X797834D03*
X795866D03*
X793897D03*
X791929D03*
X789960D03*
X787992D03*
G54D42*
X119300Y514800D03*
X136000Y625300D03*
X85400Y634916D03*
X81784Y667900D03*
X188500Y690000D03*
X171747Y704875D03*
X258823Y624546D03*
X263000Y675700D03*
X243731Y702274D03*
X218623Y652046D03*
X225400Y713000D03*
X317600Y606800D03*
X322000Y642000D03*
X314720Y678220D03*
X311704Y712120D03*
X369400Y115900D03*
X523301Y50849D03*
X622537Y30926D03*
X589104Y39667D03*
X586647Y57207D03*
X669447Y34107D03*
X845625Y177577D03*
X838972Y370969D03*
G54D108*
X606004Y44967D03*
G54D15*
X34000Y48700D03*
X73768Y58955D03*
X93614Y501552D03*
X127300Y637700D03*
X73427Y689985D03*
X115619Y707195D03*
X283032Y730636D03*
X345034Y122812D03*
X352180Y636414D03*
X294018Y659982D03*
X539108Y69241D03*
X577404Y54967D03*
X598947Y63407D03*
X641347Y57407D03*
X603747Y62107D03*
X832572Y171877D03*
G54D25*
X44206Y543876D03*
X36758Y543881D03*
X44187Y555153D03*
X36687D03*
X44000Y549500D03*
X36500D03*
X44206Y538249D03*
X36658Y538254D03*
X44106Y532622D03*
X64746Y647850D03*
X130400Y534600D03*
X140300Y529700D03*
X130400Y530300D03*
X140467Y537795D03*
X121803Y613818D03*
X126700Y599000D03*
X182439Y474031D03*
X212100Y495300D03*
X149692Y519686D03*
Y515686D03*
X203300Y503300D03*
X191528Y643963D03*
X148549Y683715D03*
X158549Y711215D03*
X271400Y474380D03*
X284445Y561694D03*
X251396Y557061D03*
X251477Y563068D03*
X267400Y553100D03*
X275825Y541121D03*
X242996Y560398D03*
Y564498D03*
X243300Y601000D03*
X243700Y589800D03*
X236100Y634300D03*
X252100Y578300D03*
X251100Y585700D03*
X252000Y573500D03*
X254125Y567260D03*
X272119Y574462D03*
X262976Y669731D03*
X238889Y662667D03*
X275420Y719420D03*
X351182Y193578D03*
X351482Y178678D03*
Y257778D03*
X343718Y232181D03*
X348500Y543800D03*
X351261Y507831D03*
X286900Y527300D03*
X287000Y522800D03*
Y535000D03*
X306453Y620550D03*
X299715Y592831D03*
X314644Y582263D03*
X348066Y594759D03*
X344200Y585500D03*
X294782Y691947D03*
X286070Y647978D03*
Y652044D03*
X345600Y672000D03*
X370680Y245508D03*
X365881Y225861D03*
X370680Y241308D03*
X367661Y475491D03*
X363002Y480368D03*
X389200Y533400D03*
X389800Y564400D03*
X366064Y635920D03*
X391200Y613900D03*
X393000Y597200D03*
X392581Y622265D03*
X493200Y42000D03*
X493600Y34000D03*
X482926Y59562D03*
X489214Y51841D03*
X589420Y50435D03*
X653746Y521683D03*
X653783Y530195D03*
X657078Y517560D03*
X737200Y426800D03*
X850011Y165178D03*
X852368Y207864D03*
Y211864D03*
X849456Y344740D03*
X848860Y403998D03*
Y395998D03*
Y399998D03*
X820100Y425800D03*
G54D61*
X197920Y712091D03*
Y736891D03*
X367700Y136500D03*
Y161300D03*
G54D70*
X275956Y653733D03*
X268456Y649858D03*
Y657608D03*
X346850Y662500D03*
X339350Y666375D03*
Y658625D03*
X496678Y61151D03*
X489178Y57276D03*
Y65026D03*
X710550Y30775D03*
Y23025D03*
X718050Y26900D03*
G54D43*
X135012Y521048D03*
X125788D03*
X135012Y514552D03*
X125788D03*
X270521Y612019D03*
X279745D03*
X270521Y618515D03*
X279745D03*
G54D109*
X605020Y51023D03*
X606988D03*
Y38911D03*
X605020D03*
G54D118*
X775160Y23465D03*
X772600D03*
X770040D03*
Y31535D03*
X772600D03*
X775160D03*
G54D127*
X877456Y322390D03*
Y357012D03*
G54D34*
X68273Y656107D03*
X65714D03*
X63155D03*
X60596D03*
Y675593D03*
X63155D03*
X65714D03*
X68273D03*
X70832Y656107D03*
Y675593D03*
X311418Y628857D03*
X308859D03*
X306300D03*
X303741D03*
X301182D03*
X300752Y700327D03*
X298193D03*
X295634D03*
X293075D03*
X290516D03*
X301182Y648343D03*
X303741D03*
X306300D03*
X308859D03*
X311418D03*
X290516Y719813D03*
X293075D03*
X295634D03*
X298193D03*
X300752D03*
G54D52*
X134700Y694850D03*
G54D16*
X61024Y34449D03*
X33464D03*
X56102Y24606D03*
X38386D03*
X108268Y44292D03*
X80708D03*
X103346Y34449D03*
X85630D03*
G54D128*
G01X66278Y550242D02*
X62527D01*
X62276Y550493D01*
G01X66278Y562841D02*
X66276D01*
X64701Y564416D01*
G01X66278Y556542D02*
X67853Y558117D01*
G01X66278Y537644D02*
X66273D01*
X65081Y538836D01*
X64427D01*
G01X66278Y559691D02*
X66276D01*
X64701Y561266D01*
G01X66278Y553392D02*
X65105D01*
X63456Y555041D01*
G01X69427Y559691D02*
Y559692D01*
X67853Y561266D01*
G01X66278Y565990D02*
X66277D01*
X64701Y567566D01*
G01Y542366D02*
X66273Y540794D01*
X66278D01*
G01Y569140D02*
X66277D01*
X64701Y570716D01*
G01X66278Y572290D02*
X67853Y573865D01*
G01X69427Y584888D02*
X67852Y586463D01*
G01X66278Y578589D02*
X66279D01*
X67853Y577015D01*
G01X66278Y575439D02*
Y575440D01*
X67853Y577015D01*
G01X66278Y584888D02*
X64703Y586463D01*
G01X69427Y569140D02*
Y569141D01*
X67853Y570715D01*
G01X91474Y550242D02*
X103400D01*
X106272Y547370D01*
G01X91474Y547093D02*
X94473D01*
G01X88325Y565990D02*
X86750Y567565D01*
G01X91474Y562841D02*
X91473D01*
X89899Y564415D01*
G01X91474Y537644D02*
Y536749D01*
X92600Y535623D01*
G01X88325Y559691D02*
X88324D01*
X86750Y561265D01*
G01X91474Y559691D02*
X91473D01*
X89899Y561265D01*
G01X91474Y553392D02*
X94720Y556638D01*
Y557158D01*
G01X89899Y567565D02*
X91474Y565990D01*
G01X85175D02*
X83600Y567565D01*
G01X91474Y540794D02*
X96371Y535897D01*
Y534124D01*
G01X69427Y575439D02*
X69428D01*
X71002Y577013D01*
G01X91474Y572290D02*
Y572293D01*
X89901Y573866D01*
X89899Y573864D01*
G01X88325Y584888D02*
Y584890D01*
X89901Y586466D01*
Y587466D01*
G01X88325Y575439D02*
X86750Y573864D01*
G01X89899D02*
X88325Y572290D01*
G01X72577Y581738D02*
X74151Y583312D01*
X74152D01*
G01X91474Y584888D02*
X91498D01*
X93051Y586441D01*
Y587466D01*
G01X88325Y569140D02*
Y569139D01*
X89899Y567565D01*
G01X91474Y575439D02*
X93049Y573864D01*
G01X91474Y581738D02*
X93048Y580164D01*
G01X184646Y555120D02*
X186220Y553546D01*
Y553543D01*
G01X203500Y516850D02*
Y513500D01*
G01X162599Y551970D02*
X161026Y553543D01*
X161023D01*
G01X164173D02*
X164172D01*
X162599Y551970D01*
G01X194093D02*
X192520Y553543D01*
X192519D01*
G01X197243Y551970D02*
X195670Y553543D01*
X195669D01*
G01X187795Y555120D02*
X189368Y556693D01*
X189370D01*
G01X200393Y551970D02*
X200392D01*
X198819Y553543D01*
G01X175196Y558269D02*
X173623Y559842D01*
X173622D01*
G01X167323Y553543D02*
X165748Y551968D01*
G01X157874Y553543D02*
X157875D01*
X159412Y552006D01*
G01X172047Y564568D02*
X173623Y562992D01*
X173622D01*
G01X197243Y589900D02*
Y589764D01*
X195669Y588190D01*
Y588189D01*
G01X157874Y585039D02*
X156299Y586614D01*
G01X198819Y591338D02*
X200393Y589764D01*
G01X203543Y574017D02*
X205118Y572442D01*
Y572441D01*
G01X209841Y596063D02*
Y596062D01*
X208267Y594488D01*
G01X205118Y581890D02*
Y581891D01*
X206692Y583465D01*
G01D02*
X205118Y585039D01*
G01X175298Y577266D02*
X173622Y575590D01*
G01X190944Y589764D02*
Y589763D01*
X189370Y588189D01*
G01X190944Y592913D02*
Y592912D01*
X189370Y591338D01*
G01X200393Y586614D02*
X198819Y585040D01*
Y585039D01*
G01X197165Y586540D02*
X196114Y585489D01*
Y585485D01*
X195669Y585040D01*
Y585039D01*
G01X312289Y535181D02*
Y534189D01*
X311249Y533149D01*
X307419D01*
G01X298219Y527239D02*
Y524869D01*
X297850Y524500D01*
G01X292024Y526434D02*
X292811Y527221D01*
Y527946D01*
X294074Y529209D01*
X298219D01*
G01X357290Y624270D02*
X353730D01*
X353500Y624500D01*
G01X328250Y581394D02*
Y580561D01*
X325172Y577483D01*
X321324D01*
G01X375720Y81700D02*
Y78680D01*
X376000Y78400D01*
G01X372714Y509275D02*
X372700D01*
Y509100D01*
X374669Y511069D01*
X377739D01*
G01X374300Y696720D02*
X379620D01*
X380900Y698000D01*
X382550D01*
G01X612110Y47920D02*
X615890D01*
X618546Y50576D01*
G54D26*
X40806Y543876D03*
X33358Y543881D03*
X40787Y555153D03*
X33287D03*
X40600Y549500D03*
X33100D03*
X40806Y538249D03*
X33258Y538254D03*
X40706Y532622D03*
X61346Y647850D03*
X127000Y534600D03*
X136900Y529700D03*
X127000Y530300D03*
X137067Y537795D03*
X118403Y613818D03*
X123300Y599000D03*
X179039Y474031D03*
X208700Y495300D03*
X146292Y519686D03*
Y515686D03*
X199900Y503300D03*
X188128Y643963D03*
X145149Y683715D03*
X155149Y711215D03*
X268000Y474380D03*
X281045Y561694D03*
X247996Y557061D03*
X248077Y563068D03*
X264000Y553100D03*
X272425Y541121D03*
X239596Y560398D03*
Y564498D03*
X283500Y527300D03*
X283600Y522800D03*
Y535000D03*
X239900Y601000D03*
X240300Y589800D03*
X232700Y634300D03*
X248700Y578300D03*
X247700Y585700D03*
X248600Y573500D03*
X250725Y567260D03*
X268719Y574462D03*
X259576Y669731D03*
X282670Y647978D03*
X235489Y662667D03*
X282670Y652044D03*
X272020Y719420D03*
X347782Y193578D03*
X348082Y178678D03*
Y257778D03*
X340318Y232181D03*
X345100Y543800D03*
X347861Y507831D03*
X303053Y620550D03*
X296315Y592831D03*
X311244Y582263D03*
X344666Y594759D03*
X340800Y585500D03*
X291382Y691947D03*
X342200Y672000D03*
X367280Y245508D03*
X362481Y225861D03*
X367280Y241308D03*
X364261Y475491D03*
X359602Y480368D03*
X385800Y533400D03*
X386400Y564400D03*
X362664Y635920D03*
X387800Y613900D03*
X389600Y597200D03*
X389181Y622265D03*
X489800Y42000D03*
X490200Y34000D03*
X479526Y59562D03*
X485814Y51841D03*
X586020Y50435D03*
X650346Y521683D03*
X650383Y530195D03*
X653678Y517560D03*
X733800Y426800D03*
X846611Y165178D03*
X848968Y207864D03*
Y211864D03*
X846056Y344740D03*
X845460Y403998D03*
Y395998D03*
Y399998D03*
X816700Y425800D03*
G54D53*
X134700Y697350D03*
G54D44*
X125600Y630800D03*
Y623200D03*
X79050Y637546D03*
Y629946D03*
X133600Y637700D03*
X91550Y654554D03*
Y662154D03*
X83750Y654654D03*
Y662254D03*
X133600Y645300D03*
X117149Y730715D03*
Y738315D03*
X109449Y730715D03*
Y738315D03*
X124820Y732391D03*
Y739991D03*
X94020Y730691D03*
Y738291D03*
X101749Y730715D03*
Y738315D03*
X132651Y732415D03*
Y740015D03*
X211800Y710100D03*
Y717700D03*
X219600Y710100D03*
Y717700D03*
X333500Y111200D03*
Y118800D03*
X332436Y627504D03*
Y635104D03*
X324636Y627604D03*
Y635204D03*
X311936Y609096D03*
Y601496D03*
X309236Y658404D03*
Y666004D03*
X317136Y658404D03*
Y666004D03*
X313870Y699174D03*
Y706774D03*
X321670Y699074D03*
Y706674D03*
X309100Y682800D03*
Y675200D03*
X306370Y731174D03*
Y738774D03*
X298470Y731174D03*
Y738774D03*
X663847Y39907D03*
Y32307D03*
X655847Y39907D03*
Y32307D03*
X898622Y76514D03*
Y68914D03*
X890622Y76514D03*
Y68914D03*
X882622Y76514D03*
Y68914D03*
X899491Y398439D03*
Y406039D03*
X891794Y398441D03*
Y406041D03*
X884102Y398456D03*
Y406056D03*
X899597Y384357D03*
Y391957D03*
G54D62*
X180190Y728775D03*
X158304D03*
G54D35*
X55971Y660732D03*
Y663291D03*
Y665850D03*
Y668409D03*
Y670968D03*
X75457D03*
Y668409D03*
Y665850D03*
Y663291D03*
Y660732D03*
X296557Y633482D03*
Y636041D03*
X316043D03*
Y633482D03*
X285891Y704952D03*
Y707511D03*
X305377D03*
Y704952D03*
X296557Y638600D03*
Y641159D03*
Y643718D03*
X316043D03*
Y641159D03*
Y638600D03*
X285891Y710070D03*
Y712629D03*
Y715188D03*
X305377D03*
Y712629D03*
Y710070D03*
G54D80*
X355739Y565469D03*
Y562909D03*
Y560349D03*
Y557789D03*
Y555229D03*
Y552669D03*
Y550109D03*
Y547549D03*
X321324Y564683D03*
Y562123D03*
Y559563D03*
Y557003D03*
Y554443D03*
X299124D03*
Y557003D03*
Y559563D03*
Y562123D03*
Y564683D03*
X355739Y575709D03*
Y573149D03*
Y570589D03*
Y568029D03*
X321324Y577483D03*
Y574923D03*
Y572363D03*
Y569803D03*
Y567243D03*
X299124D03*
Y569803D03*
Y572363D03*
Y574923D03*
Y577483D03*
X352100Y673680D03*
Y676240D03*
Y678800D03*
Y681360D03*
Y683920D03*
Y686480D03*
Y689040D03*
Y691600D03*
Y694160D03*
Y696720D03*
X377939Y547549D03*
Y550109D03*
Y552669D03*
Y555229D03*
Y557789D03*
Y560349D03*
Y562909D03*
Y565469D03*
Y568029D03*
Y570589D03*
Y573149D03*
Y575709D03*
X374300Y696720D03*
Y694160D03*
Y691600D03*
Y689040D03*
Y686480D03*
Y683920D03*
Y681360D03*
Y678800D03*
Y676240D03*
Y673680D03*
G54D17*
X43000Y48500D03*
Y54500D03*
X82768Y58755D03*
Y64755D03*
X277600Y674600D03*
Y665600D03*
G54D71*
X346457Y57007D03*
X353543Y62913D03*
Y55039D03*
X346457Y66850D03*
Y74724D03*
Y84567D03*
X353543Y86535D03*
Y78661D03*
Y70787D03*
G54D119*
X724200Y398380D03*
X807100Y397380D03*
G54D129*
G01X138900Y525999D02*
X118499D01*
X116050Y523550D01*
Y513250D01*
X117800Y511500D01*
X119400D01*
G01X135012Y510200D02*
X120700D01*
X119400Y511500D01*
G01X232300Y712600D02*
Y704300D01*
X229050Y701050D01*
X184184D01*
X174949Y691815D01*
G01X341210Y602420D02*
Y600020D01*
X337750Y596560D01*
G01X318762Y593351D02*
X321088D01*
X322250Y594513D01*
Y599000D01*
G01X331250Y591440D02*
Y590038D01*
X328250Y587038D01*
Y585000D01*
G01X369095Y203549D02*
X371413D01*
X373073Y201889D01*
G01X362150Y214174D02*
X363975Y212349D01*
Y210049D01*
G01X370220Y580586D02*
X372984Y583350D01*
X374600D01*
G01X390961Y577031D02*
X393869D01*
X394300Y576600D01*
G54D45*
X90854Y639150D03*
X98454D03*
X86983Y674124D03*
X94583D03*
X86983Y682024D03*
X94583D03*
X90854Y647050D03*
X98454D03*
X87900Y722700D03*
X95500D03*
X243324Y623114D03*
X250924D03*
X322740Y619400D03*
X330340D03*
X322740Y611500D03*
X330340D03*
X320774Y684270D03*
X328374D03*
X320774Y691970D03*
X328374D03*
X514972Y26680D03*
X522572D03*
X503854Y42093D03*
X511454D03*
X511465Y34432D03*
X503865D03*
X609257Y23971D03*
X616857D03*
X613247Y77407D03*
X620847D03*
X613247Y69307D03*
X620847D03*
X888313Y201350D03*
X895913D03*
X887184Y192800D03*
X894784D03*
X885492Y209135D03*
X893092D03*
X885492Y216835D03*
X893092D03*
X891166Y381316D03*
X883566D03*
G54D18*
X51000Y52000D03*
X62000D03*
X90768Y62255D03*
X101768D03*
X243199Y718747D03*
X232199D03*
X243199Y728347D03*
X232199D03*
X243199Y737947D03*
X232199D03*
X605847Y77007D03*
X594847D03*
G54D63*
X281645Y546834D03*
Y549394D03*
Y551954D03*
X274245D03*
Y549394D03*
Y546834D03*
G54D81*
X298219Y527239D03*
Y529209D03*
Y531179D03*
Y533149D03*
X307419D03*
Y531179D03*
Y529209D03*
Y527239D03*
X377739Y515004D03*
Y513039D03*
Y511069D03*
Y509099D03*
Y507134D03*
X361439D03*
Y509099D03*
Y511069D03*
Y513039D03*
Y515004D03*
G54D90*
X372000Y68800D03*
G54D54*
G01X274245Y549394D02*
X270021D01*
G01X260931Y692574D02*
Y698331D01*
X261900Y699300D01*
G01X276360Y686350D02*
X279350D01*
X279400Y686400D01*
G01X271240Y692850D02*
Y698960D01*
G01X251091Y686274D02*
X253426D01*
X254600Y685100D01*
G01X263491Y686074D02*
Y679741D01*
X263000Y679250D01*
G01X257000Y698900D02*
Y697071D01*
X258371Y695700D01*
Y692574D01*
G01X257000Y698900D02*
X258371Y700271D01*
Y704714D01*
X258431Y704774D01*
G01X372000Y62150D02*
X375300D01*
G01X372000Y72050D02*
X375300D01*
X154724Y537795D03*
Y540945D03*
Y544094D03*
X157874Y537795D03*
Y540945D03*
Y544094D03*
X161023Y537795D03*
Y540945D03*
Y544094D03*
X154724Y597638D03*
Y600787D03*
Y603937D03*
X157874Y597638D03*
Y600787D03*
Y603937D03*
X161023Y597638D03*
Y600787D03*
Y603937D03*
X214567Y537795D03*
Y540945D03*
Y544094D03*
X217716Y537795D03*
Y540945D03*
Y544094D03*
X220866Y537795D03*
Y540945D03*
Y544094D03*
X214567Y597638D03*
Y600787D03*
Y603937D03*
X217716Y597638D03*
Y600787D03*
Y603937D03*
X220866Y597638D03*
Y600787D03*
Y603937D03*
G54D27*
G01X58926Y582407D02*
X58955Y582378D01*
X61168D01*
G01D02*
X61808Y581738D01*
X66278D01*
G01X203542Y545671D02*
X203541D01*
X201968Y547244D01*
G01X195669Y540945D02*
X197243Y539371D01*
G01X194093Y567718D02*
X195669Y566142D01*
G01X194093Y564569D02*
Y564568D01*
X192519Y562994D01*
Y562992D01*
G01X195669D02*
Y562993D01*
X194093Y564569D01*
G01D02*
X194092D01*
X192519Y566142D01*
G01X189370Y562992D02*
Y562994D01*
X190944Y564568D01*
Y564569D01*
G01D02*
Y564656D01*
X189458Y566142D01*
X189370D01*
G01X186220Y556693D02*
X184647Y555120D01*
X184646D01*
G01X153149Y536221D02*
X153150D01*
X154724Y537795D01*
G01X167323Y556693D02*
X165748Y558268D01*
G01X172048Y555120D02*
X172049D01*
X173622Y556693D01*
G01X186220Y562992D02*
X185494Y562266D01*
X183797D01*
X183071Y562992D01*
G01X187925Y564617D02*
Y564296D01*
X186621Y562992D01*
X186220D01*
G01X187746Y567669D02*
Y567668D01*
X186220Y566142D01*
G01X184595Y567666D02*
X183071Y566142D01*
G01X167323Y562992D02*
X168898Y561417D01*
G01X206692Y555120D02*
X206691D01*
X205118Y556693D01*
G01X157874Y559842D02*
X157872D01*
X156297Y558267D01*
G01X181497Y551970D02*
X181498D01*
X183071Y553543D01*
G01X175197Y551970D02*
X175198D01*
X176771Y553543D01*
G01X178347Y551970D02*
X178348D01*
X179921Y553543D01*
G01X203542Y555120D02*
X201969Y556693D01*
X201968D01*
G01X206692Y558269D02*
X206691D01*
X205118Y559842D01*
G01X206692Y561419D02*
X206691D01*
X205118Y562992D01*
G01X206692Y564569D02*
X206691D01*
X205118Y566142D01*
G01X173622D02*
X173621D01*
X172047Y564568D01*
G01X173622Y578740D02*
Y578652D01*
X172020Y577050D01*
G01X203463Y605450D02*
X201968Y603955D01*
Y603937D01*
G01X198819Y594488D02*
X198818D01*
X197243Y592913D01*
Y592912D01*
X195669Y591338D01*
G01X190944Y577166D02*
X190945D01*
X192519Y578740D01*
G01X195669D02*
X194743Y579666D01*
X193445D01*
X192519Y578740D01*
G01X194093Y574016D02*
Y574015D01*
X192519Y572441D01*
G01X195669D02*
X195668D01*
X194093Y574016D01*
G01D02*
X194094D01*
X195668Y575590D01*
X195669D01*
G01X194093Y567718D02*
X194092D01*
X192519Y569291D01*
G01X195669D02*
X195667D01*
X194094Y567718D01*
X194093D01*
G01X189370Y572441D02*
X190944Y574015D01*
Y574016D01*
G01D02*
X190945D01*
X192519Y575590D01*
G01X190944Y567718D02*
X190943D01*
X189370Y569291D01*
G01Y578740D02*
X187796Y577166D01*
X187795D01*
G01D02*
X187794D01*
X186220Y578740D01*
G01X184646Y577166D02*
X184645D01*
X183071Y578740D01*
G01X172048Y589764D02*
Y589763D01*
X173622Y588189D01*
G01X168898Y589764D02*
Y589763D01*
X170472Y588189D01*
G01X186220Y575590D02*
X186318D01*
X187843Y574065D01*
X187844D01*
G01D02*
X187845D01*
X189370Y575590D01*
G01X184645Y574166D02*
Y574016D01*
X183071Y575590D01*
G01X186220Y572441D02*
Y572591D01*
X184645Y574166D01*
G01D02*
X184895D01*
X183170Y572441D01*
X183071D01*
G01X184595Y567666D02*
X186220Y569291D01*
G01X184695Y567666D02*
X184595D01*
G01X184646Y570867D02*
X183071Y569292D01*
Y569291D01*
G01X167323D02*
X168898Y570866D01*
G01D02*
X170472Y572440D01*
Y572441D01*
G01X157874Y578740D02*
X156299Y580315D01*
G01X157874Y572441D02*
X156299Y570866D01*
G01X200393Y589764D02*
Y589763D01*
X198819Y588189D01*
G01X186220D02*
Y588188D01*
X187794Y586614D01*
G01D02*
X186220Y585040D01*
Y585039D01*
G01X203542Y589764D02*
Y589763D01*
X201968Y588189D01*
G01X200393Y596063D02*
X198819Y597637D01*
Y597638D01*
G01Y594488D02*
X200393Y596062D01*
Y596063D01*
G01X187795Y592914D02*
X187794D01*
X186220Y594488D01*
G01X167323Y575590D02*
X170472Y572441D01*
G01X175196Y589764D02*
Y589763D01*
X173622Y588189D01*
G01D02*
Y585039D01*
G01X165748Y583464D02*
X167322Y581890D01*
X167323D01*
G01X209842Y583464D02*
X208268Y581890D01*
X208267D01*
G01X187900Y589800D02*
X186362Y591338D01*
X186220D01*
G01X173622Y572441D02*
X173621D01*
X172047Y570867D01*
G01X176771Y588189D02*
X176772D01*
X178347Y589764D01*
G01D02*
Y589763D01*
X179921Y588189D01*
G01X181497Y589764D02*
Y589763D01*
X183071Y588189D01*
G01X194093Y586614D02*
Y586613D01*
X192519Y585039D01*
G01X206692Y567600D02*
Y567717D01*
X205118Y569291D01*
G01X173622Y581890D02*
X174671D01*
X176095Y580466D01*
Y578063D01*
X175298Y577266D01*
G01X173622Y569291D02*
X173621D01*
X172047Y567717D01*
G01X281645Y549394D02*
X285800D01*
G01X214567Y588189D02*
X212992Y586614D01*
G01X216141D02*
Y586613D01*
X214567Y585039D01*
G01X307542Y588138D02*
X307635Y588231D01*
X312262D01*
G01X364600Y491950D02*
X364920D01*
X366720Y493750D01*
X370140D01*
G01X777500Y34500D02*
X775160Y32160D01*
Y31535D01*
G01X770040Y23465D02*
X767665D01*
X766200Y22000D01*
X66278Y540794D03*
Y543943D03*
Y537644D03*
Y547093D03*
Y550242D03*
Y553392D03*
Y556542D03*
Y559691D03*
Y562841D03*
Y565990D03*
Y578589D03*
Y581738D03*
Y584888D03*
Y569140D03*
Y572290D03*
Y575439D03*
X85175Y547093D03*
X91474Y540794D03*
X88325D03*
X85175D03*
X91474Y543943D03*
X88325D03*
X85175D03*
X91474Y537644D03*
X88325D03*
X85175D03*
X72577Y540794D03*
X69427D03*
X72577Y543943D03*
X69427D03*
X72577Y537644D03*
X69427D03*
X91474Y547093D03*
X88325D03*
X72577D03*
X69427D03*
X91474Y550242D03*
X88325D03*
X85175D03*
X72577D03*
X69427D03*
X91474Y553392D03*
X88325D03*
X85175D03*
X72577D03*
X69427D03*
X91474Y556542D03*
X88325D03*
X85175D03*
X72577D03*
X69427D03*
X91474Y559691D03*
X88325D03*
X85175D03*
X72577D03*
X69427D03*
X91474Y562841D03*
X88325D03*
X85175D03*
X72577D03*
X69427D03*
X91474Y565990D03*
X88325D03*
X85175D03*
X72577D03*
X69427D03*
X91474Y569140D03*
Y572290D03*
Y575439D03*
Y578589D03*
Y581738D03*
Y584888D03*
X88325Y578589D03*
X85175D03*
X88325Y581738D03*
X85175D03*
X88325Y584888D03*
X85175D03*
X72577Y578589D03*
X69427D03*
X72577Y581738D03*
X69427D03*
X72577Y584888D03*
X69427D03*
X88325Y569140D03*
X85175D03*
X72577D03*
X69427D03*
X88325Y572290D03*
X85175D03*
X72577D03*
X69427D03*
X88325Y575439D03*
X85175D03*
X72577D03*
X69427D03*
X154724Y547244D03*
Y550394D03*
Y553543D03*
Y556693D03*
Y559842D03*
Y562992D03*
X157874Y547244D03*
Y550394D03*
Y553543D03*
Y556693D03*
Y559842D03*
Y562992D03*
X161023Y547244D03*
Y550394D03*
Y553543D03*
Y556693D03*
Y559842D03*
Y562992D03*
X164173Y537795D03*
Y540945D03*
Y544094D03*
Y547244D03*
Y550394D03*
Y553543D03*
Y556693D03*
Y559842D03*
Y562992D03*
X167323Y537795D03*
Y540945D03*
Y544094D03*
Y547244D03*
Y550394D03*
Y553543D03*
Y556693D03*
Y559842D03*
Y562992D03*
X170472Y537795D03*
Y540945D03*
Y544094D03*
Y547244D03*
Y550394D03*
Y553543D03*
Y556693D03*
Y559842D03*
Y562992D03*
X173622Y537795D03*
Y540945D03*
Y544094D03*
Y547244D03*
Y550394D03*
Y553543D03*
Y556693D03*
Y559842D03*
Y562992D03*
X176771Y537795D03*
Y540945D03*
Y544094D03*
Y547244D03*
Y550394D03*
Y553543D03*
Y556693D03*
X179921Y537795D03*
Y540945D03*
Y544094D03*
Y547244D03*
Y550394D03*
Y553543D03*
Y556693D03*
Y562992D03*
X183071Y537795D03*
Y540945D03*
Y544094D03*
Y547244D03*
Y550394D03*
Y553543D03*
Y556693D03*
Y562992D03*
X186220Y537795D03*
Y540945D03*
Y544094D03*
Y547244D03*
Y550394D03*
Y553543D03*
Y556693D03*
Y562992D03*
X189370Y537795D03*
Y540945D03*
Y544094D03*
Y547244D03*
Y550394D03*
Y553543D03*
Y556693D03*
Y562992D03*
X192519Y537795D03*
Y540945D03*
Y544094D03*
Y547244D03*
Y550394D03*
Y553543D03*
Y556693D03*
Y562992D03*
X195669Y537795D03*
Y540945D03*
Y544094D03*
Y547244D03*
Y550394D03*
Y553543D03*
Y556693D03*
Y562992D03*
X198819Y537795D03*
Y540945D03*
Y544094D03*
Y547244D03*
Y550394D03*
Y553543D03*
Y556693D03*
X201968Y537795D03*
Y540945D03*
Y544094D03*
Y547244D03*
Y550394D03*
Y553543D03*
Y556693D03*
Y559842D03*
Y562992D03*
X205118Y537795D03*
Y540945D03*
Y544094D03*
Y547244D03*
Y550394D03*
Y553543D03*
Y556693D03*
Y559842D03*
Y562992D03*
X208267Y537795D03*
Y540945D03*
Y544094D03*
Y547244D03*
Y550394D03*
Y553543D03*
Y556693D03*
Y559842D03*
Y562992D03*
X211417Y537795D03*
Y540945D03*
Y544094D03*
Y547244D03*
Y550394D03*
Y553543D03*
Y556693D03*
Y559842D03*
Y562992D03*
X154724Y566142D03*
Y569291D03*
Y572441D03*
Y575590D03*
Y578740D03*
Y581890D03*
Y585039D03*
Y588189D03*
Y591338D03*
Y594488D03*
X157874Y566142D03*
Y569291D03*
Y572441D03*
Y575590D03*
Y578740D03*
Y581890D03*
Y585039D03*
Y588189D03*
Y591338D03*
Y594488D03*
X161023Y566142D03*
Y569291D03*
Y572441D03*
Y575590D03*
Y578740D03*
Y581890D03*
Y585039D03*
Y588189D03*
Y591338D03*
Y594488D03*
X164173Y566142D03*
Y569291D03*
Y572441D03*
Y575590D03*
Y578740D03*
Y581890D03*
Y585039D03*
Y588189D03*
Y591338D03*
Y594488D03*
Y597638D03*
Y600787D03*
Y603937D03*
X167323Y566142D03*
Y569291D03*
Y572441D03*
Y575590D03*
Y578740D03*
Y581890D03*
Y585039D03*
Y588189D03*
Y591338D03*
Y594488D03*
Y597638D03*
Y600787D03*
Y603937D03*
X170472Y566142D03*
Y569291D03*
Y572441D03*
Y575590D03*
Y578740D03*
Y581890D03*
Y585039D03*
Y588189D03*
Y591338D03*
Y594488D03*
Y597638D03*
Y600787D03*
Y603937D03*
X173622Y566142D03*
Y569291D03*
Y572441D03*
Y575590D03*
Y578740D03*
Y581890D03*
Y585039D03*
Y588189D03*
Y591338D03*
Y594488D03*
Y597638D03*
Y600787D03*
Y603937D03*
X176771Y585039D03*
Y588189D03*
Y591338D03*
Y594488D03*
Y597638D03*
Y600787D03*
Y603937D03*
X179921Y566142D03*
Y569291D03*
Y572441D03*
Y575590D03*
Y578740D03*
Y585039D03*
Y588189D03*
Y591338D03*
Y594488D03*
Y597638D03*
Y600787D03*
Y603937D03*
X183071Y566142D03*
Y569291D03*
Y572441D03*
Y575590D03*
Y578740D03*
Y585039D03*
Y588189D03*
Y591338D03*
Y594488D03*
Y597638D03*
Y600787D03*
Y603937D03*
X186220Y566142D03*
Y569291D03*
Y572441D03*
Y575590D03*
Y578740D03*
Y585039D03*
Y588189D03*
Y591338D03*
Y594488D03*
Y597638D03*
Y600787D03*
Y603937D03*
X189370Y566142D03*
Y569291D03*
Y572441D03*
Y575590D03*
Y578740D03*
Y585039D03*
Y588189D03*
Y591338D03*
Y594488D03*
Y597638D03*
Y600787D03*
Y603937D03*
X192519Y566142D03*
Y569291D03*
Y572441D03*
Y575590D03*
Y578740D03*
Y585039D03*
Y588189D03*
Y591338D03*
Y594488D03*
Y597638D03*
Y600787D03*
Y603937D03*
X195669Y566142D03*
Y569291D03*
Y572441D03*
Y575590D03*
Y578740D03*
Y585039D03*
Y588189D03*
Y591338D03*
Y594488D03*
Y597638D03*
Y600787D03*
Y603937D03*
X198819Y585039D03*
Y588189D03*
Y591338D03*
Y594488D03*
Y597638D03*
Y600787D03*
Y603937D03*
X201968Y566142D03*
Y569291D03*
Y572441D03*
Y575590D03*
Y578740D03*
Y581890D03*
Y585039D03*
Y588189D03*
Y591338D03*
Y594488D03*
Y597638D03*
Y600787D03*
Y603937D03*
X205118Y566142D03*
Y569291D03*
Y572441D03*
Y575590D03*
Y578740D03*
Y581890D03*
Y585039D03*
Y588189D03*
Y591338D03*
Y594488D03*
Y597638D03*
Y600787D03*
Y603937D03*
X208267Y566142D03*
Y569291D03*
Y572441D03*
Y575590D03*
Y578740D03*
Y581890D03*
Y585039D03*
Y588189D03*
Y591338D03*
Y594488D03*
Y597638D03*
Y600787D03*
Y603937D03*
X211417Y566142D03*
Y569291D03*
Y572441D03*
Y575590D03*
Y578740D03*
Y581890D03*
Y585039D03*
Y588189D03*
Y591338D03*
Y594488D03*
Y597638D03*
Y600787D03*
Y603937D03*
X214567Y547244D03*
Y550394D03*
Y553543D03*
Y556693D03*
Y559842D03*
Y562992D03*
X217716Y547244D03*
Y550394D03*
Y553543D03*
Y556693D03*
Y559842D03*
Y562992D03*
X220866Y547244D03*
Y550394D03*
Y553543D03*
Y556693D03*
Y559842D03*
Y562992D03*
X214567Y566142D03*
Y569291D03*
Y572441D03*
Y575590D03*
Y578740D03*
Y581890D03*
Y585039D03*
Y588189D03*
Y591338D03*
Y594488D03*
X217716Y566142D03*
Y569291D03*
Y572441D03*
Y575590D03*
Y578740D03*
Y581890D03*
Y585039D03*
Y588189D03*
Y591338D03*
Y594488D03*
X220866Y566142D03*
Y569291D03*
Y572441D03*
Y575590D03*
Y578740D03*
Y581890D03*
Y585039D03*
Y588189D03*
Y591338D03*
Y594488D03*
G54D36*
X60600Y670900D03*
X65900Y671000D03*
X65714Y665850D03*
X60800Y660900D03*
X60700Y665900D03*
X65700Y660900D03*
X139916Y709422D03*
X130019Y709695D03*
X139916Y705822D03*
X130019Y706095D03*
X135019D03*
X70700Y671000D03*
X70800Y660700D03*
X70600Y665800D03*
X139916Y713022D03*
Y716622D03*
Y720222D03*
Y723822D03*
X130019Y713295D03*
Y716895D03*
Y720495D03*
X135019Y710595D03*
Y723595D03*
Y719095D03*
Y714845D03*
X130019Y724095D03*
X265400Y446100D03*
X312289Y535181D03*
X311386Y633450D03*
X306300Y638600D03*
X301286Y638650D03*
X301386Y633650D03*
X306286D03*
X311186Y638550D03*
X300720Y704920D03*
X300520Y710020D03*
X290620Y710120D03*
X295634Y710070D03*
X290720Y705120D03*
X295620D03*
X301186Y643650D03*
X306486Y643750D03*
X311286D03*
X300620Y715220D03*
X290520Y715120D03*
X295820Y715220D03*
X365164Y612620D03*
X358864D03*
X371400Y606400D03*
X358800Y606300D03*
X365300Y606500D03*
X371400Y612700D03*
X371300Y618800D03*
X365500Y619000D03*
X358900Y618800D03*
X468000Y31500D03*
Y39500D03*
X464000Y35500D03*
X468000Y35400D03*
X472000Y35500D03*
X603943Y42806D03*
X608143Y42906D03*
X603943Y47006D03*
X608043D03*
X706275Y445986D03*
X753800Y535000D03*
X857020Y383172D03*
Y379572D03*
Y386772D03*
X875272Y186265D03*
X878872D03*
X860872D03*
X871672D03*
X868072D03*
X864472D03*
X878372Y191265D03*
X878872Y196265D03*
X864472D03*
X868072D03*
X871672D03*
X875272D03*
X865372Y191265D03*
X873872D03*
X869622D03*
X860872Y196265D03*
Y191265D03*
X871420Y383172D03*
X875020D03*
Y379572D03*
X871420D03*
X867820D03*
X860620D03*
X864220D03*
X875020Y386772D03*
X871420D03*
X867820D03*
X860620D03*
X864220D03*
X867820Y383172D03*
X860620D03*
X864220D03*
G54D72*
X339331Y49803D03*
X360669Y91929D03*
G54D91*
X372000Y65400D03*
G54D82*
X312262Y593351D03*
Y590791D03*
Y588231D03*
X318762D03*
Y593351D03*
X337750Y591440D03*
Y594000D03*
Y596560D03*
X331250D03*
Y591440D03*
G54D73*
X339331Y91929D03*
X360669Y49803D03*
G54D46*
X131900Y624300D03*
X340034Y112312D03*
X345034D03*
X370220Y580786D03*
X509055Y22402D03*
X504381Y22399D03*
X631781Y57411D03*
G54D64*
X250624Y629614D03*
X786900Y25000D03*
X851620Y366572D03*
X866768Y210564D03*
X863120Y405672D03*
G54D37*
X108500Y482200D03*
X101113Y522777D03*
X101100Y515300D03*
X81032Y517477D03*
X81068Y509866D03*
X69778Y517477D03*
X69900Y510000D03*
X75405Y517477D03*
X75373Y509879D03*
X86673Y510000D03*
X92000Y517400D03*
X86659Y517477D03*
X93531Y496341D03*
X119600Y628800D03*
X117349Y697047D03*
X121449Y694247D03*
X113349Y697047D03*
X184924Y493148D03*
X157896Y519319D03*
X161902Y519349D03*
X142000Y515500D03*
X186537Y519381D03*
X182474Y520691D03*
X166280Y520400D03*
X170380D03*
X191400Y505800D03*
X194649Y520351D03*
X190600Y519400D03*
X178469Y521393D03*
X195500Y506200D03*
X174400Y516100D03*
X212000Y502700D03*
X186976Y636468D03*
X191076Y636598D03*
X170600Y637200D03*
X174700D03*
X178776Y636468D03*
X182876D03*
X153700Y626200D03*
X155849Y699115D03*
X211706Y641392D03*
X158349Y706915D03*
X225262Y518580D03*
X258969Y544921D03*
X247900Y616800D03*
X258000Y649664D03*
X232000Y642600D03*
X219200Y642200D03*
X271200Y676100D03*
X250800Y679300D03*
X262645Y708235D03*
X258500Y679200D03*
X238807Y658571D03*
X342497Y524061D03*
X345100Y539600D03*
X324500Y537200D03*
X320000D03*
X352480Y587564D03*
X286703Y618411D03*
X347680Y639664D03*
X387458Y74149D03*
X391458D03*
X360382Y193600D03*
X388489Y555935D03*
X378800Y583800D03*
X383000D03*
X356680Y589064D03*
X443457Y53415D03*
X594504Y60667D03*
X636647Y60307D03*
X723800Y33100D03*
Y25400D03*
X720017Y478614D03*
X716100Y438800D03*
X721100D03*
X842168Y188614D03*
X858622Y162514D03*
X850730Y357478D03*
X853060Y407698D03*
X823728Y477000D03*
X804000Y437800D03*
X799000D03*
G54D19*
X66435Y8514D03*
X61435D03*
X56435D03*
X51435D03*
X46435D03*
X41435D03*
X36435D03*
X31435D03*
X26435D03*
X21435D03*
X16435D03*
X8514Y10593D03*
Y15593D03*
Y20593D03*
Y25593D03*
Y30593D03*
Y35593D03*
Y40593D03*
Y45593D03*
Y50593D03*
Y55593D03*
Y60593D03*
Y65593D03*
Y70593D03*
Y75593D03*
Y80593D03*
Y85593D03*
Y90593D03*
Y95593D03*
Y100593D03*
Y105593D03*
Y110593D03*
Y115593D03*
Y120593D03*
Y125593D03*
Y130593D03*
Y135593D03*
Y140593D03*
Y145593D03*
Y150593D03*
Y155593D03*
Y160593D03*
Y165593D03*
Y170593D03*
Y175593D03*
Y180593D03*
Y185593D03*
Y190593D03*
Y195593D03*
Y200593D03*
Y205593D03*
Y210593D03*
Y215593D03*
Y220593D03*
Y225593D03*
Y230593D03*
Y235593D03*
Y240593D03*
Y245593D03*
Y250593D03*
Y255593D03*
Y260593D03*
Y265593D03*
Y270593D03*
Y275593D03*
Y280593D03*
Y285593D03*
Y290593D03*
Y295593D03*
Y300593D03*
Y305593D03*
Y310593D03*
Y315593D03*
Y320593D03*
Y325593D03*
Y330593D03*
Y335593D03*
Y340593D03*
Y345593D03*
Y350593D03*
Y355593D03*
Y360593D03*
Y365593D03*
Y370593D03*
Y375593D03*
Y380593D03*
Y385593D03*
Y390593D03*
Y395593D03*
Y400593D03*
Y405593D03*
Y410593D03*
Y415593D03*
Y420593D03*
Y425593D03*
Y430593D03*
Y435593D03*
Y440593D03*
Y445593D03*
Y450593D03*
Y455593D03*
Y460593D03*
Y465593D03*
Y470593D03*
Y475593D03*
Y480593D03*
Y485593D03*
Y490593D03*
Y495593D03*
Y500593D03*
Y505593D03*
Y510593D03*
Y515593D03*
Y520593D03*
Y525593D03*
Y530593D03*
Y535593D03*
Y540593D03*
Y545593D03*
Y550593D03*
Y555593D03*
Y560593D03*
Y565593D03*
Y570593D03*
Y575593D03*
Y580593D03*
Y585593D03*
Y590593D03*
Y595593D03*
Y600593D03*
Y605593D03*
Y610593D03*
Y615593D03*
Y620593D03*
Y625593D03*
Y630593D03*
Y635593D03*
Y640593D03*
Y645593D03*
Y650593D03*
Y655593D03*
Y660593D03*
Y665593D03*
Y670593D03*
Y675593D03*
Y680593D03*
Y685593D03*
Y690593D03*
Y695593D03*
Y700593D03*
Y705593D03*
Y710593D03*
Y715593D03*
Y720593D03*
X9942Y725256D03*
X12178Y729728D03*
X14414Y734200D03*
X16650Y738672D03*
X18886Y743144D03*
X21122Y747617D03*
X23358Y752089D03*
X111683Y63266D03*
Y58266D03*
Y23266D03*
Y18266D03*
Y13266D03*
X111435Y8514D03*
X106435D03*
X101435D03*
X96435D03*
X91435D03*
X86435D03*
X81435D03*
X76435D03*
X71435D03*
X111683Y118266D03*
Y113266D03*
Y108266D03*
Y103266D03*
Y98266D03*
Y93266D03*
Y88266D03*
Y83266D03*
Y78266D03*
Y73266D03*
Y68266D03*
Y203266D03*
Y198266D03*
Y193266D03*
Y188266D03*
Y183266D03*
Y178266D03*
Y173266D03*
Y168266D03*
Y163266D03*
Y158266D03*
Y153266D03*
Y148266D03*
Y278266D03*
Y273266D03*
Y268266D03*
Y263266D03*
Y258266D03*
Y253266D03*
Y248266D03*
Y243266D03*
Y238266D03*
Y233266D03*
Y228266D03*
Y223266D03*
Y218266D03*
Y213266D03*
Y208266D03*
Y348266D03*
Y343266D03*
Y338266D03*
Y333266D03*
Y328266D03*
Y323266D03*
Y318266D03*
Y313266D03*
Y308266D03*
Y303266D03*
Y298266D03*
Y293266D03*
Y288266D03*
Y283266D03*
Y418266D03*
Y413266D03*
Y408266D03*
Y403266D03*
Y398266D03*
Y393266D03*
Y388266D03*
Y383266D03*
Y378266D03*
Y373266D03*
Y368266D03*
Y363266D03*
Y358266D03*
Y353266D03*
X140090Y621027D03*
X103940Y635460D03*
X76118Y625275D03*
X81118D03*
X86300Y703200D03*
X99337Y683756D03*
Y678756D03*
Y673756D03*
X86300Y708000D03*
X95200Y667500D03*
X90400D03*
X85600D03*
X76549Y680547D03*
Y675547D03*
X81549Y680547D03*
Y675547D03*
X134223Y691027D03*
X122335Y660582D03*
Y655782D03*
X76395Y755266D03*
X81395D03*
X86395D03*
X91395D03*
X96395D03*
X101395D03*
X106395D03*
X111395D03*
X116395D03*
X121395D03*
X126395D03*
X131395D03*
X136395D03*
X141395D03*
X108928Y744775D03*
X113928D03*
X118928D03*
X123928D03*
X103928D03*
X98928D03*
X93928D03*
X83125Y719240D03*
Y724040D03*
X202800Y510100D03*
X208100Y515200D03*
X208000Y520500D03*
X178800Y513400D03*
X160100Y622300D03*
X161900Y627800D03*
X167400Y618300D03*
X165800Y623700D03*
X206636Y618649D03*
X196700Y704985D03*
X201700D03*
X206700D03*
X211700D03*
X191700D03*
X146395Y755266D03*
X151395D03*
X156395D03*
X161395D03*
X166395D03*
X171395D03*
X176395D03*
X181395D03*
X186395D03*
X191395D03*
X196395D03*
X201395D03*
X206395D03*
X211395D03*
X155400Y717700D03*
X241100Y544100D03*
X238100Y550800D03*
X247300Y544000D03*
X235700Y544500D03*
X237980Y555707D03*
X217134Y521103D03*
X238168Y529269D03*
X235658Y534262D03*
X221898Y618622D03*
X235614Y609978D03*
X221700Y704985D03*
X226700D03*
X216700D03*
X216395Y755266D03*
X221395D03*
X226395D03*
X231395D03*
X236395D03*
X241395D03*
X246395D03*
X251395D03*
X256395D03*
X261395D03*
X266395D03*
X271395D03*
X276395D03*
X281395D03*
X249200Y733700D03*
Y728700D03*
Y723700D03*
Y718700D03*
Y738500D03*
X330546Y8514D03*
X325546D03*
X320546D03*
X315546D03*
X310546D03*
X305546D03*
X300546D03*
X296034Y9002D03*
Y14002D03*
Y19002D03*
Y24002D03*
Y29002D03*
Y34002D03*
Y39002D03*
Y44002D03*
Y49002D03*
Y54002D03*
Y59002D03*
Y64002D03*
Y69002D03*
Y74002D03*
Y79002D03*
Y84002D03*
Y89002D03*
Y94002D03*
Y99002D03*
Y104002D03*
Y109002D03*
Y114002D03*
Y119002D03*
Y124002D03*
Y129002D03*
Y134002D03*
Y139002D03*
X334782Y184928D03*
X321182Y202574D03*
Y197774D03*
X305882Y195474D03*
X305382Y190174D03*
X334882Y195478D03*
Y200478D03*
Y190478D03*
X335061Y222578D03*
X335100Y218378D03*
X323492Y214234D03*
X305862Y210014D03*
X335000Y621200D03*
Y615400D03*
Y610200D03*
X325600Y640100D03*
X330400D03*
X335200D03*
X322000Y653081D03*
X312400D03*
X317200D03*
X307600D03*
X298700Y674600D03*
X303700D03*
X286395Y755266D03*
X291395D03*
X296395D03*
X301395D03*
X306395D03*
X311395D03*
X316395D03*
X321395D03*
X326395D03*
X331395D03*
X336395D03*
X315520Y711720D03*
X320320D03*
X325120D03*
X305559Y720973D03*
X310559D03*
X305559Y725973D03*
X310559D03*
X299500Y725400D03*
X373073Y201889D03*
X369100Y592006D03*
X399754Y706071D03*
X389168Y743572D03*
X391404Y739100D03*
X393640Y734628D03*
X395876Y730156D03*
X398112Y725684D03*
X399754Y716071D03*
Y711071D03*
X435000Y29000D03*
X438500Y25500D03*
Y32500D03*
X491500Y71600D03*
X496500D03*
X491500Y76600D03*
X496500D03*
X556510Y53626D03*
X516693Y46345D03*
X521493D03*
X516693Y41545D03*
X521493D03*
Y36745D03*
X516693D03*
X521493Y31945D03*
X526530Y43775D03*
X516693Y31945D03*
X567700Y28240D03*
X548550Y76480D03*
X525000Y76300D03*
X525200Y80900D03*
X556710Y64726D03*
X543750Y76480D03*
X506500Y76600D03*
X501500D03*
Y71600D03*
X608847Y34607D03*
X614032Y33307D03*
X621747Y63307D03*
X626647Y77507D03*
Y72507D03*
Y67507D03*
X593017Y69796D03*
X588217Y74596D03*
Y69796D03*
X576624Y193205D03*
Y198205D03*
Y203205D03*
Y208205D03*
Y213205D03*
Y223205D03*
Y228205D03*
Y233205D03*
Y238205D03*
Y243205D03*
Y248205D03*
Y253205D03*
Y258205D03*
Y263205D03*
Y268205D03*
Y273205D03*
Y278205D03*
Y333205D03*
Y338205D03*
Y343205D03*
Y348205D03*
Y353205D03*
Y358205D03*
Y363205D03*
Y368205D03*
Y373205D03*
Y378205D03*
Y383205D03*
Y388205D03*
Y393205D03*
Y398205D03*
Y403205D03*
Y408205D03*
Y413205D03*
Y418205D03*
Y423205D03*
Y428205D03*
Y433205D03*
Y438205D03*
Y443205D03*
Y448205D03*
Y498205D03*
Y503205D03*
Y508205D03*
Y513205D03*
Y518205D03*
Y523205D03*
Y528205D03*
Y533205D03*
Y538205D03*
Y543205D03*
Y548205D03*
Y553205D03*
Y558205D03*
Y563205D03*
Y568205D03*
Y573205D03*
Y578205D03*
Y583205D03*
Y588205D03*
X578710Y592712D03*
X580946Y597184D03*
X583182Y601656D03*
X585418Y606129D03*
X587654Y610601D03*
X635975Y621407D03*
X640975D03*
X715546Y8514D03*
X710546D03*
X705546D03*
X700546D03*
X695546D03*
X668847Y27107D03*
X663847D03*
X658847D03*
X653847D03*
X653601Y46761D03*
X658601D03*
X653601Y51761D03*
X658601D03*
X663601Y46761D03*
Y51761D03*
X668601Y46761D03*
Y51761D03*
X700065Y135985D03*
Y125985D03*
Y115985D03*
X710065D03*
Y125985D03*
Y135985D03*
X649590Y114036D03*
X700065Y155985D03*
X710065D03*
Y145985D03*
X696159Y225829D03*
X698909Y278104D03*
X700065Y265985D03*
Y255985D03*
Y245985D03*
Y235985D03*
X710065D03*
Y245985D03*
Y255985D03*
Y265985D03*
X709625Y275991D03*
X710065Y325985D03*
Y315985D03*
X711574Y285985D03*
X708307Y295429D03*
X710065Y305985D03*
Y335985D03*
Y345985D03*
X700065Y385985D03*
Y395985D03*
Y405985D03*
Y415985D03*
X710065Y375985D03*
Y355985D03*
Y365985D03*
Y455985D03*
X684399Y466984D03*
Y471984D03*
X663500Y484000D03*
Y489000D03*
Y494000D03*
X692282Y476720D03*
X689875Y464586D03*
X698275Y438305D03*
X683100Y485200D03*
X679832Y494100D03*
Y489100D03*
X679100Y483300D03*
X674900D03*
X674832Y489100D03*
Y494100D03*
X682800Y480700D03*
X693392Y520482D03*
X683392D03*
X688392D03*
X705080Y521247D03*
X694272Y495786D03*
X645975Y621407D03*
X650975D03*
X655975D03*
X660975D03*
X665975D03*
X670975D03*
X675975D03*
X680975D03*
X685975D03*
X690975D03*
X695975D03*
X700975D03*
X705975D03*
X710975D03*
X715975D03*
X785546Y8514D03*
X780546D03*
X775546D03*
X770546D03*
X765546D03*
X760546D03*
X755546D03*
X750546D03*
X745546D03*
X740546D03*
X735546D03*
X730546D03*
X725546D03*
X720546D03*
X770065Y55985D03*
Y65985D03*
Y75985D03*
X750065Y85985D03*
X770065D03*
X760065D03*
X740065D03*
X730065Y95985D03*
X760065D03*
X780065D03*
X770065D03*
Y105985D03*
X780065D03*
Y115985D03*
X730065Y135985D03*
Y125985D03*
Y115985D03*
Y105985D03*
X750065Y95985D03*
X740065D03*
X750065Y105985D03*
X760065D03*
X740065D03*
X750065Y115985D03*
X760065D03*
X770065D03*
X740065D03*
X750065Y125985D03*
X760065D03*
X770065D03*
X780065D03*
X740065D03*
X750065Y135985D03*
X760065D03*
X770065D03*
X780065D03*
X740065D03*
X720065Y105985D03*
Y115985D03*
Y125985D03*
Y135985D03*
Y155985D03*
X780065D03*
X730065D03*
Y145985D03*
X750065D03*
X760065D03*
X770065D03*
X780065D03*
X740065D03*
X750065Y155985D03*
X760065D03*
X770065D03*
X740065D03*
X750065Y165985D03*
X760065D03*
X770065D03*
X740065D03*
X750065Y175985D03*
X760065D03*
X770065D03*
X740065D03*
X750065Y185985D03*
X760065D03*
X770065D03*
X740065D03*
X750065Y195985D03*
X760065D03*
X770065D03*
X740065D03*
X750065Y205985D03*
X760065D03*
X770065D03*
X740065D03*
X720065Y145985D03*
X730065Y215985D03*
X773469Y277001D03*
X780065Y275985D03*
X787817Y275879D03*
X750065Y215985D03*
X760065D03*
X770065D03*
X780065D03*
X740065D03*
X780065Y265985D03*
Y255985D03*
Y245985D03*
Y235985D03*
Y225985D03*
X770065Y265985D03*
Y255985D03*
Y245985D03*
Y235985D03*
Y225985D03*
X763133Y275881D03*
X759790Y263326D03*
X760065Y255985D03*
Y245985D03*
Y235985D03*
Y225985D03*
X750065Y275985D03*
Y265985D03*
Y255985D03*
Y245985D03*
Y235985D03*
Y225985D03*
X741608Y277171D03*
X740065Y265985D03*
Y255985D03*
Y245985D03*
Y235985D03*
Y225985D03*
X730830Y276087D03*
X730065Y265985D03*
Y255985D03*
X731766Y246017D03*
X730065Y235985D03*
X730190Y223549D03*
X720237Y223228D03*
X720065Y235985D03*
X721766Y246017D03*
X720065Y255985D03*
Y265985D03*
X718617Y275736D03*
X770065Y335985D03*
X760065D03*
X720065Y325985D03*
X760065D03*
X750065D03*
X740065D03*
X730065D03*
X720065Y315985D03*
X780065Y285985D03*
X770065D03*
X760065D03*
X750065Y295985D03*
X760065D03*
X770065D03*
X780065D03*
Y305985D03*
Y315985D03*
Y325985D03*
Y335985D03*
Y345985D03*
X770065Y305985D03*
Y315985D03*
Y325985D03*
Y345985D03*
X760065Y305985D03*
Y315985D03*
Y345985D03*
X750065Y305985D03*
Y315985D03*
Y335985D03*
Y345985D03*
X740065Y305985D03*
Y315985D03*
Y335985D03*
Y345985D03*
X730065D03*
Y335985D03*
Y315985D03*
X752500Y286000D03*
X740065Y295985D03*
X741000Y286000D03*
X730065Y305985D03*
X729486Y296094D03*
X729294Y285987D03*
X721574Y285985D03*
X719049Y296011D03*
X720065Y305985D03*
Y335985D03*
Y345985D03*
X750065Y415985D03*
X760065D03*
X770065D03*
X780065D03*
X730065D03*
X740065D03*
X750065Y405985D03*
X760065D03*
X770065D03*
X780065D03*
X730065D03*
X740065D03*
X780065Y395985D03*
X770065D03*
X760065D03*
X750065D03*
X740065D03*
X730065D03*
X720065Y375985D03*
X730065Y365985D03*
Y375985D03*
Y385985D03*
X750065D03*
X760065D03*
X770065D03*
X780065D03*
X740065D03*
X750065Y375985D03*
X760065D03*
X770065D03*
X780065D03*
X740065D03*
X750065Y365985D03*
X760065D03*
X770065D03*
X780065D03*
X740065D03*
X780065Y355985D03*
X770065D03*
X760065D03*
X750065D03*
X740065D03*
X730065D03*
X720065D03*
Y365985D03*
Y455985D03*
Y465985D03*
X750065D03*
X760065D03*
X770065D03*
X780065D03*
X730065D03*
X740065D03*
X780065Y455985D03*
X770065D03*
X760065D03*
X750065D03*
X740065D03*
X730065D03*
X750065Y445985D03*
X760065D03*
X770065D03*
X780065D03*
X730065D03*
X740065D03*
X750065Y435985D03*
X760065D03*
X770065D03*
X780065D03*
X740065D03*
X750065Y425985D03*
X760065D03*
X770065D03*
X780065D03*
X736217Y493664D03*
X776658Y489380D03*
X771658D03*
X781658D03*
Y494380D03*
X741217Y493664D03*
X776658Y494380D03*
X771658D03*
X740900Y553600D03*
X741000Y547700D03*
X784604Y519082D03*
X758512Y534430D03*
X747107Y536580D03*
X739334Y524156D03*
X752602Y517850D03*
X736580Y507734D03*
X788015Y507785D03*
X783015D03*
X747602Y517850D03*
X731580Y507734D03*
X716578Y509762D03*
X721590Y511659D03*
X726590D03*
X720975Y621407D03*
X725975D03*
X730975D03*
X735975D03*
X740975D03*
X745975D03*
X750975D03*
X755975D03*
X760975D03*
X765975D03*
X770975D03*
X775975D03*
X780975D03*
X785975D03*
X850546Y8514D03*
X845546D03*
X840546D03*
X835546D03*
X830546D03*
X825546D03*
X820546D03*
X815546D03*
X810546D03*
X805546D03*
X800546D03*
X795546D03*
X790546D03*
X820065Y105985D03*
Y135985D03*
Y125985D03*
Y115985D03*
X810065Y135985D03*
Y125985D03*
Y115985D03*
X790065Y105985D03*
X800065Y115985D03*
X790065D03*
Y125985D03*
X800065D03*
Y135985D03*
X790065D03*
X853436Y108917D03*
Y113717D03*
X853435Y90260D03*
Y95060D03*
X820065Y155985D03*
X810065D03*
X800065D03*
X790065D03*
X820065Y145985D03*
X810065D03*
X790065D03*
X800065D03*
X820313Y276188D03*
X810065Y275985D03*
X800065D03*
X820065Y265985D03*
Y255985D03*
Y245985D03*
Y235985D03*
Y225985D03*
X810065Y265985D03*
Y255985D03*
Y245985D03*
Y235985D03*
X800065Y265985D03*
Y255985D03*
Y245985D03*
Y235985D03*
X790065Y265985D03*
Y255985D03*
Y245985D03*
Y235985D03*
Y225985D03*
X857965Y273150D03*
X820065Y305985D03*
Y295985D03*
Y285985D03*
X810065Y295985D03*
Y285985D03*
X800065D03*
X790065D03*
Y295985D03*
X800065D03*
X810065Y305985D03*
X810000Y314000D03*
X810065Y325985D03*
X800065Y305985D03*
Y315985D03*
Y325985D03*
Y335985D03*
Y345985D03*
X790065Y305985D03*
Y315985D03*
Y325985D03*
X791500Y336000D03*
X790065Y345985D03*
X859407Y300314D03*
Y309914D03*
Y305114D03*
Y295314D03*
Y290314D03*
Y285314D03*
X790065Y415985D03*
Y405985D03*
Y395985D03*
Y375985D03*
X800065D03*
X790065Y365985D03*
X800065D03*
Y355985D03*
X790065D03*
X830426Y482939D03*
X835949Y482890D03*
X800065Y455985D03*
Y465985D03*
X790065D03*
Y455985D03*
Y445985D03*
Y435985D03*
X790191Y426486D03*
X809000Y429400D03*
X840057Y494320D03*
X835057D03*
X805771Y518743D03*
X789604Y519082D03*
X794604D03*
X836023Y508124D03*
X825161Y507954D03*
X820161D03*
X815161D03*
X805983Y508293D03*
X793015Y507785D03*
X790975Y621407D03*
X795975D03*
X800975D03*
X805975D03*
X810975D03*
X815975D03*
X820975D03*
X825975D03*
X830975D03*
X835975D03*
X840975D03*
X854971Y637313D03*
Y642313D03*
Y647313D03*
Y652313D03*
Y657313D03*
Y662313D03*
Y667313D03*
Y672313D03*
Y677313D03*
Y682313D03*
Y687313D03*
Y692313D03*
Y697313D03*
Y702313D03*
Y707313D03*
Y712313D03*
X916683Y62377D03*
Y57377D03*
Y52377D03*
Y47377D03*
Y42377D03*
Y37377D03*
Y32377D03*
Y27377D03*
Y22377D03*
Y17377D03*
X915546Y8514D03*
X910546D03*
X905546D03*
X900546D03*
X883222Y59214D03*
X888022D03*
X892822D03*
X897622D03*
X880922Y63714D03*
X885722D03*
X890522D03*
X895322D03*
X900122D03*
X916683Y132377D03*
Y127377D03*
Y122377D03*
Y117377D03*
Y112377D03*
Y107377D03*
Y102377D03*
Y97377D03*
Y92377D03*
Y87377D03*
Y82377D03*
Y77377D03*
Y72377D03*
Y67377D03*
X897250Y81510D03*
X902050D03*
Y86310D03*
X897250D03*
Y91110D03*
X902050D03*
X897250Y95910D03*
X902050D03*
X916683Y207377D03*
Y202377D03*
Y197377D03*
Y192377D03*
Y187377D03*
Y182377D03*
Y177377D03*
Y172377D03*
Y167377D03*
Y162377D03*
Y157377D03*
Y152377D03*
Y147377D03*
Y142377D03*
Y137377D03*
X900600Y201239D03*
X897803Y207684D03*
X902803D03*
X880222Y206781D03*
X875222D03*
X916683Y277377D03*
Y272377D03*
Y267377D03*
Y262377D03*
Y257377D03*
Y252377D03*
Y247377D03*
Y242377D03*
Y237377D03*
Y232377D03*
Y227377D03*
Y222377D03*
Y217377D03*
Y212377D03*
X897195Y275688D03*
X902195D03*
Y270688D03*
X897195D03*
X897803Y217684D03*
Y212684D03*
X902803Y217684D03*
Y212684D03*
X896031Y228468D03*
Y223468D03*
X891031D03*
Y228468D03*
Y238468D03*
X896031D03*
X891031Y233468D03*
X896031D03*
X868376Y271313D03*
X873376D03*
X880122Y216781D03*
X875122D03*
X880222Y211781D03*
X875222D03*
X916683Y347377D03*
Y342377D03*
Y337377D03*
Y332377D03*
Y327377D03*
Y322377D03*
Y317377D03*
Y312377D03*
Y307377D03*
Y302377D03*
Y297377D03*
Y292377D03*
Y287377D03*
Y282377D03*
X896030Y296330D03*
X901030D03*
X900995Y290712D03*
X895995D03*
X900819Y316367D03*
X895819D03*
X900716Y311058D03*
X895716D03*
X864207Y300314D03*
Y309914D03*
Y305114D03*
Y295314D03*
Y290314D03*
Y285314D03*
X916683Y422377D03*
Y417377D03*
Y412377D03*
Y407377D03*
Y402377D03*
Y397377D03*
Y392377D03*
Y387377D03*
Y382377D03*
Y377377D03*
Y372377D03*
Y367377D03*
Y362377D03*
Y357377D03*
Y352377D03*
X876451Y407949D03*
X880665Y410841D03*
X885665D03*
X890665D03*
X895665D03*
X900665D03*
X902091Y369397D03*
X897091D03*
X902091Y374397D03*
X897091D03*
Y379397D03*
X902091D03*
X888548Y392923D03*
X883548D03*
X893548D03*
X888548Y387923D03*
X893548D03*
X883548D03*
X916683Y492377D03*
Y487377D03*
Y482377D03*
Y477377D03*
Y472377D03*
Y467377D03*
Y462377D03*
Y457377D03*
Y452377D03*
Y447377D03*
Y442377D03*
Y437377D03*
Y432377D03*
Y427377D03*
Y562377D03*
Y557377D03*
Y552377D03*
Y547377D03*
Y542377D03*
Y537377D03*
Y532377D03*
Y527377D03*
Y522377D03*
Y517377D03*
Y512377D03*
Y507377D03*
Y502377D03*
Y497377D03*
Y637377D03*
Y632377D03*
Y627377D03*
Y622377D03*
Y617377D03*
Y612377D03*
Y607377D03*
Y602377D03*
Y597377D03*
Y592377D03*
Y587377D03*
Y582377D03*
Y577377D03*
Y572377D03*
Y567377D03*
Y707377D03*
Y702377D03*
Y697377D03*
Y692377D03*
Y687377D03*
Y682377D03*
Y677377D03*
Y672377D03*
Y667377D03*
Y662377D03*
Y657377D03*
Y652377D03*
Y647377D03*
Y642377D03*
X901041Y753684D03*
X903277Y749212D03*
X905513Y744740D03*
X907749Y740268D03*
X909985Y735796D03*
X912221Y731323D03*
X914457Y726851D03*
X916683Y722377D03*
Y717377D03*
Y712377D03*
G54D55*
G01X357800Y702960D02*
X352800D01*
G01X366800Y710440D02*
X370840D01*
X372100Y711700D01*
X168898Y548819D03*
X184645Y539370D03*
X194094D03*
X203542Y545671D03*
X197243Y539371D03*
X194093Y564569D03*
X190944D03*
X194093Y555120D03*
X184646D03*
X153149Y536221D03*
X165748Y558268D03*
X172048Y555120D03*
X156297Y558267D03*
X187925Y564617D03*
X168898Y561417D03*
X206692Y555120D03*
X165745Y564567D03*
X168895D03*
X159449Y561417D03*
X165748D03*
X172047D03*
X162598Y558268D03*
X168898D03*
X165748Y555118D03*
X159449D03*
X162599Y551970D03*
X194093D03*
X197243D03*
X181497D03*
X175197D03*
X178347D03*
X203542Y555120D03*
X187795D03*
X200393Y551970D03*
X206692Y558269D03*
Y561419D03*
Y564569D03*
X175196Y558269D03*
X190945Y545669D03*
X172047D03*
Y551970D03*
X159449Y545671D03*
X162599Y545669D03*
X165749D03*
X212991Y561419D03*
X184646Y548821D03*
Y545671D03*
X184645Y542519D03*
X206693Y542520D03*
X159449Y542521D03*
X171906Y534661D03*
X212991Y542519D03*
X156299Y545671D03*
X165749Y548819D03*
X175197Y545671D03*
X162599Y542519D03*
X168898D03*
X156299Y542521D03*
X181496Y542520D03*
X159449Y548821D03*
X194094Y542519D03*
X172047Y548819D03*
X168898Y551969D03*
X162599Y548821D03*
X162598Y561417D03*
X168898Y555119D03*
X181497Y548821D03*
X178346Y545670D03*
X181497Y545671D03*
X162595Y564567D03*
X203542Y551970D03*
X181497Y555120D03*
X178346Y555119D03*
X187885Y552058D03*
X197245Y555118D03*
X159412Y552006D03*
X165748Y551968D03*
X178347Y564569D03*
X203543Y561418D03*
Y564568D03*
X172047D03*
X200393Y548819D03*
X209842Y545669D03*
Y564567D03*
Y558268D03*
X212992Y551969D03*
Y548819D03*
X209842Y561417D03*
X212992Y564567D03*
X200393Y545669D03*
X206692Y545671D03*
X209842Y548819D03*
X212992Y545669D03*
X165777Y542555D03*
X209842Y555119D03*
Y551969D03*
X206692Y548820D03*
X206693Y551969D03*
X194094Y545669D03*
Y548820D03*
X175197Y548821D03*
X168898Y545669D03*
X153150Y539371D03*
X153149Y542521D03*
X197244Y545669D03*
Y542519D03*
X156300Y539371D03*
X197243Y589900D03*
X194094Y602362D03*
X206692Y596063D03*
X203450Y592912D03*
X194093Y596063D03*
X172020Y577050D03*
X175196Y589764D03*
X190944Y577166D03*
X194093Y574016D03*
Y567718D03*
X190944Y574016D03*
Y567718D03*
X187795Y577166D03*
X184646D03*
X172048Y589764D03*
X168898D03*
X187844Y574065D03*
X184645Y574166D03*
X187746Y567669D03*
X184695Y567666D03*
X184646Y570867D03*
X168898Y570866D03*
X156299Y586614D03*
Y580315D03*
X159449Y567717D03*
X156299Y570866D03*
X200393Y589764D03*
X187900Y589800D03*
X187794Y586614D03*
X203542Y589764D03*
X200393Y596063D03*
X187795Y592914D03*
X203605Y605821D03*
X187795Y602363D03*
X153149Y605513D03*
X206692Y592913D03*
X165748Y583464D03*
X209842D03*
X212992Y586614D03*
X212991Y567718D03*
X209841Y574016D03*
X206692D03*
X168898Y567717D03*
X159449Y570866D03*
X168898Y583464D03*
Y577165D03*
X159449Y586614D03*
X162598Y580315D03*
Y586614D03*
X165748D03*
X168898D03*
X159449Y577165D03*
X156299D03*
X168898Y580315D03*
X159449D03*
X162598Y577165D03*
X165748Y580315D03*
X162598Y583464D03*
X165748Y570866D03*
Y567717D03*
X162598D03*
X172047Y570867D03*
X194094Y577166D03*
X203543Y574017D03*
X178347Y589764D03*
X181497D03*
X194093Y586614D03*
X209841Y596063D03*
X206692Y583465D03*
Y567600D03*
X212992Y580315D03*
X212991Y577165D03*
X209842Y567717D03*
X212991Y574016D03*
X190945Y599213D03*
X190944Y596063D03*
X187796Y599212D03*
X181586Y599123D03*
X212991Y583465D03*
X209841Y577165D03*
X159448Y596063D03*
X190944Y602362D03*
X203543D03*
X203542Y596063D03*
X194094Y599213D03*
X168898Y596063D03*
X212992Y602363D03*
X212991Y599212D03*
X206692Y589763D03*
X168898Y592913D03*
X162598Y596063D03*
X194093Y589764D03*
Y592913D03*
X206692Y586614D03*
X209842Y586613D03*
X212992Y589764D03*
X209841Y592913D03*
X162598Y570866D03*
X178347Y574018D03*
X203542Y580315D03*
Y586614D03*
X190944D03*
X178346Y586615D03*
X181497Y586614D03*
X178344Y577166D03*
X203542Y577165D03*
X178347Y570769D03*
X203501Y571005D03*
X175298Y577266D03*
X172047Y567717D03*
X178346Y596064D03*
X178347Y599213D03*
X165748D03*
X168898D03*
X162598D03*
X159448D03*
X172048Y596063D03*
X190944Y592913D03*
Y589764D03*
X200393Y586614D03*
X197165Y586540D03*
X212993Y592912D03*
X209842Y589763D03*
X206692Y580315D03*
X209841D03*
X181500Y595900D03*
X200393Y592912D03*
X209841Y599212D03*
X200393D03*
X159448Y589764D03*
Y592913D03*
X162598Y589764D03*
X165748D03*
Y596063D03*
Y592913D03*
X175197D03*
X172048D03*
X181530Y592765D03*
X175197Y596063D03*
Y599213D03*
X172048D03*
X216141Y564569D03*
Y561419D03*
X219291Y542519D03*
X216141D03*
X216142Y548820D03*
X216141Y555120D03*
Y558269D03*
X222441Y548820D03*
X219291D03*
X216141Y551970D03*
X216142Y545669D03*
X216141Y580315D03*
X222440Y605512D03*
X216141Y577165D03*
Y583465D03*
Y586614D03*
Y567718D03*
X219293Y567717D03*
X216141Y574016D03*
Y599212D03*
Y589762D03*
X230600Y608100D03*
X355600Y172900D03*
X363400Y115950D03*
X815600Y386200D03*
G54D28*
X56844Y588651D03*
X28971Y675883D03*
X43800Y675800D03*
X55895Y643491D03*
X49500Y659909D03*
X130500Y599000D03*
X128800Y611100D03*
X140800Y616400D03*
X88266Y621165D03*
X127263Y594662D03*
X138473Y603273D03*
X128800Y694400D03*
X118477Y702077D03*
X122100Y698500D03*
X112850Y641488D03*
X112403Y656627D03*
X77903Y689785D03*
X73265Y647355D03*
X83450Y646620D03*
X139000Y740015D03*
X104132Y722843D03*
X199000Y479500D03*
X196100Y524600D03*
X200300Y525500D03*
X188158Y527500D03*
X192800Y529100D03*
X179021Y528902D03*
X173175Y528444D03*
X169420Y526499D03*
X183350Y527900D03*
X165572Y529088D03*
X154151Y523478D03*
X160743Y527786D03*
X153985Y527761D03*
X144800Y549100D03*
X204979Y525545D03*
X213050Y525000D03*
X204843Y623300D03*
X200000Y618900D03*
X212750Y618700D03*
X191435Y614794D03*
X187221Y617507D03*
X182819Y617616D03*
X176993Y613763D03*
X175300Y618200D03*
X172048Y614508D03*
X161958Y633782D03*
X143221Y611975D03*
X149800Y618700D03*
X147262Y615302D03*
X144993Y626564D03*
X142500Y599062D03*
X155378Y618114D03*
X210800Y622500D03*
X157450Y626650D03*
X193000Y648700D03*
X160200Y699165D03*
X143100Y696800D03*
X144048Y735514D03*
X276995Y558100D03*
X230838Y566081D03*
X235484Y561538D03*
X260513Y564135D03*
X266700Y548600D03*
X250901Y531106D03*
X258969Y537520D03*
X221014Y526000D03*
X237344Y513444D03*
X233900Y516000D03*
X271966Y565966D03*
X266325Y557905D03*
X228541Y529541D03*
X243950Y522900D03*
X231800Y538900D03*
X229762Y522829D03*
X219800Y517100D03*
X242449Y532550D03*
X254560Y548551D03*
X253202Y544298D03*
X223593Y634091D03*
X234797Y568900D03*
X236421Y574788D03*
X235310Y585700D03*
X234034Y578517D03*
X246433Y567987D03*
X260131Y574893D03*
X217600Y620700D03*
X226300Y618800D03*
X237800Y629800D03*
X250087Y591300D03*
X236056Y596885D03*
X238700Y617900D03*
X255935Y583784D03*
X242866Y577122D03*
X261455Y579009D03*
X239963Y613061D03*
X260500Y637500D03*
X261025Y593260D03*
X239000Y687300D03*
X257000Y698900D03*
X281602Y657563D03*
X258400Y662000D03*
X279920Y703460D03*
X252400Y705750D03*
X262335Y653750D03*
X239842Y681600D03*
X252700Y643400D03*
X270100Y662700D03*
X222306Y737851D03*
X221987Y728528D03*
X279900Y715400D03*
X261305Y715957D03*
X339900Y123700D03*
X343292Y187765D03*
X338955Y179994D03*
X342228Y247493D03*
X341105Y237114D03*
X340000Y262678D03*
X343582Y271028D03*
X339387Y241609D03*
X350900Y485348D03*
X353700Y480668D03*
X350300Y443500D03*
X356502Y474400D03*
X338963Y440163D03*
X347800Y440100D03*
X288100Y542900D03*
X288883Y555249D03*
X349600Y539100D03*
X345864Y531341D03*
X351500Y524125D03*
X313791Y550221D03*
X330100Y559544D03*
X309592Y550099D03*
X327900Y555900D03*
X330188Y563900D03*
X322800Y549300D03*
X320700Y543250D03*
X336800Y545700D03*
X349422Y553098D03*
X348597Y548003D03*
X336800Y510000D03*
X297999Y550096D03*
X322000Y520700D03*
X341596Y500750D03*
X290889Y530299D03*
X316000Y530000D03*
X290889Y525299D03*
Y535299D03*
X316000Y536000D03*
X351300Y504000D03*
X298613Y597750D03*
X347451Y576772D03*
X349373Y571300D03*
X346577Y567339D03*
X327874Y576249D03*
X342300Y571800D03*
X328200D03*
X330200Y568100D03*
X303166Y599583D03*
X298500Y622200D03*
X316500Y618500D03*
X288771Y637726D03*
X344616Y590187D03*
X320937Y582655D03*
X306766Y582469D03*
X339304Y709335D03*
X285773Y657061D03*
X294018Y655000D03*
X290500Y644700D03*
X286007Y692279D03*
X310000Y690500D03*
X345977Y684410D03*
X345671Y680190D03*
X303279Y670477D03*
X328723Y674658D03*
X334673Y672886D03*
X287600Y726400D03*
X418487Y71447D03*
X428740Y179528D03*
X366300Y190000D03*
X374890Y177173D03*
X369882Y225923D03*
X358050Y254056D03*
X362349Y255239D03*
X357846Y260273D03*
X363100Y220900D03*
X382500Y339800D03*
X382800Y353300D03*
X392800Y491900D03*
X376544Y460678D03*
X364275Y486275D03*
X386000Y485700D03*
X397388Y479012D03*
X383600Y473500D03*
X380113Y480400D03*
X391129Y448629D03*
X372300Y478900D03*
X367552Y480084D03*
X385600Y537300D03*
X387517Y560556D03*
X391700Y507300D03*
X386400Y609500D03*
X357200Y592900D03*
X374522Y591597D03*
X383500Y588800D03*
X383400Y598800D03*
X379100Y588400D03*
X384025Y594525D03*
X383500Y604900D03*
X388700Y633400D03*
X384200Y626000D03*
X384495Y569100D03*
X383944Y573339D03*
X364900Y581500D03*
X380700Y684096D03*
X380800Y679800D03*
Y675600D03*
X381593Y694069D03*
X497137Y42455D03*
X450900Y29000D03*
Y24000D03*
X474400Y56600D03*
X468800Y57000D03*
X485585Y34890D03*
X451231Y41843D03*
X450832Y50121D03*
X485300Y27500D03*
X453400Y19100D03*
X477171Y51517D03*
X483347Y63650D03*
X493238Y52126D03*
X450200Y34416D03*
X448226Y45257D03*
X460442Y53761D03*
X484513Y22548D03*
X481353Y18104D03*
X498100Y34000D03*
X477129Y66151D03*
X460800Y66850D03*
X457086Y179528D03*
X442913D03*
X471260D03*
X519493Y50899D03*
X519517Y55714D03*
X524672Y18026D03*
X515337Y20945D03*
X556300Y47148D03*
X545000Y63300D03*
X513779Y179528D03*
X527953D03*
X542126D03*
X556299D03*
X622364Y24999D03*
X618546Y50576D03*
X582232Y60757D03*
X598656Y30307D03*
X593347Y43217D03*
X621691Y40136D03*
X626700Y60200D03*
X598513Y57106D03*
X593247Y47907D03*
X593563Y24910D03*
X604047Y57707D03*
X609247Y63207D03*
X673140Y41600D03*
X695544Y21750D03*
X703300Y30100D03*
X697305Y28963D03*
X713200Y399200D03*
X712851Y483089D03*
X678474Y478005D03*
X710633Y463904D03*
X644559Y528060D03*
X729900Y26900D03*
X774200Y37200D03*
X781100Y19400D03*
X731437Y21928D03*
X718200Y399200D03*
X716100Y430500D03*
X721100D03*
X728900Y426800D03*
X720017Y483158D03*
X734761Y470838D03*
X852682Y74813D03*
X858373Y174835D03*
X842508Y145014D03*
X856468Y207064D03*
X853750Y181603D03*
X837195Y177710D03*
X856196Y212359D03*
X838169Y337936D03*
X801100Y398200D03*
X796100D03*
X845111Y362071D03*
X857706Y399786D03*
X852716Y399376D03*
X847820Y375672D03*
X830809Y371019D03*
X799000Y429500D03*
X804000D03*
X811800Y425800D03*
X811099Y481767D03*
X823728Y481512D03*
X903755Y100137D03*
X887928Y177932D03*
X894711Y187059D03*
X871261Y218621D03*
X882745Y369882D03*
X890963Y375283D03*
G54D56*
X169149Y691815D03*
X357882Y185174D03*
X450488Y54522D03*
X433255Y47144D03*
X433257Y42488D03*
X433246Y51800D03*
X579304Y45967D03*
X603447Y30307D03*
X781400Y29800D03*
X840322Y160314D03*
X848622Y145014D03*
X844706Y340240D03*
X820768Y371019D03*
G54D83*
X353514Y604746D03*
Y620494D03*
X376814D03*
Y604746D03*
G54D92*
X357290Y624270D03*
X373038D03*
Y600970D03*
X357290D03*
G54D74*
X354000Y119740D03*
Y116000D03*
Y112260D03*
X357800Y706700D03*
Y702960D03*
Y710440D03*
X363000Y112260D03*
Y119740D03*
X366800Y702960D03*
Y710440D03*
G54D47*
X131900Y629900D03*
X340034Y117912D03*
X345034D03*
X370220Y586386D03*
X509055Y28002D03*
X504381Y27999D03*
X631781Y63011D03*
G54D65*
X245024Y629614D03*
X781300Y25000D03*
X857520Y405672D03*
X846020Y366572D03*
X861168Y210564D03*
G54D29*
X41452Y659909D03*
X179037Y463761D03*
X208200Y626900D03*
X145049Y687715D03*
X268300Y465400D03*
X254958Y589579D03*
X281370Y637250D03*
X246925Y633776D03*
X272203Y704337D03*
X274600Y640772D03*
X259500Y666000D03*
X347682Y189778D03*
X290095Y539294D03*
X316000Y526100D03*
X328200Y581394D03*
Y585000D03*
X385500Y541100D03*
X387411Y577031D03*
X366614Y639820D03*
X382500Y698000D03*
X375900Y710400D03*
X479426Y55778D03*
X489700Y38000D03*
X468786Y53022D03*
X549200Y61200D03*
X614247Y63107D03*
G54D38*
X108500Y478800D03*
X93531Y492941D03*
X101113Y519377D03*
X101100Y511900D03*
X81032Y514077D03*
X81068Y506466D03*
X69778Y514077D03*
X69900Y506600D03*
X75405Y514077D03*
X75373Y506479D03*
X86673Y506600D03*
X92000Y514000D03*
X86659Y514077D03*
X119600Y625400D03*
X117349Y693647D03*
X121449Y690847D03*
X113349Y693647D03*
X184924Y489748D03*
X157896Y515919D03*
X161902Y515949D03*
X142000Y512100D03*
X186537Y515981D03*
X182474Y517291D03*
X166280Y517000D03*
X170380D03*
X191400Y502400D03*
X194649Y516951D03*
X190600Y516000D03*
X178469Y517993D03*
X195500Y502800D03*
X174400Y512700D03*
X212000Y499300D03*
X211706Y637992D03*
X186976Y633068D03*
X191076Y633198D03*
X170600Y633800D03*
X174700D03*
X178776Y633068D03*
X182876D03*
X153700Y622800D03*
X155849Y695715D03*
X158349Y703515D03*
X225262Y515180D03*
X258969Y541521D03*
X247900Y613400D03*
X258000Y646264D03*
X232000Y639200D03*
X219200Y638800D03*
X271200Y672700D03*
X250800Y675900D03*
X262645Y704835D03*
X258500Y675800D03*
X238807Y655171D03*
X342497Y520661D03*
X345100Y536200D03*
X324500Y533800D03*
X320000D03*
X347680Y636264D03*
X352480Y584164D03*
X286703Y615011D03*
X387458Y70749D03*
X391458D03*
X360382Y190200D03*
X388489Y552535D03*
X378800Y580400D03*
X383000D03*
X356680Y585664D03*
X443457Y50015D03*
X594504Y57267D03*
X636647Y56907D03*
X723800Y29700D03*
Y22000D03*
X720017Y475214D03*
X716100Y435400D03*
X721100D03*
X842168Y185214D03*
X858622Y159114D03*
X850730Y354078D03*
X853060Y404298D03*
X823728Y473600D03*
X804000Y434400D03*
X799000D03*
G54D48*
X119400Y638900D03*
X123100D03*
X207900Y637900D03*
X215406Y637892D03*
X228200Y639100D03*
X282600Y682100D03*
X258000Y653700D03*
X297767Y582318D03*
X294167D03*
X336631Y681726D03*
X370650Y190014D03*
X364600Y491900D03*
X849625Y177677D03*
X842984Y370969D03*
X893974Y179135D03*
X890639Y367560D03*
X878439Y400923D03*
G54D66*
X251091Y692774D03*
X248531D03*
X245971D03*
Y686274D03*
X251091D03*
X271240Y686350D03*
X273800D03*
X276360D03*
Y692850D03*
X271240D03*
X263491Y692574D03*
X260931D03*
X258371D03*
Y686074D03*
X263491D03*
X363975Y203549D03*
X369095D03*
Y210049D03*
X366535D03*
X363975D03*
X370140Y487250D03*
X372700D03*
X375260D03*
Y493750D03*
X370140D03*
G54D39*
X124290Y490300D03*
Y485300D03*
Y480300D03*
Y475300D03*
Y470300D03*
Y465300D03*
Y460300D03*
Y495300D03*
X161440Y460300D03*
Y465300D03*
Y470300D03*
Y475300D03*
Y480300D03*
Y485300D03*
Y490300D03*
Y495300D03*
X258375Y460300D03*
Y465300D03*
Y470300D03*
Y475300D03*
Y480300D03*
Y485300D03*
Y490300D03*
X221225D03*
Y485300D03*
Y480300D03*
Y475300D03*
Y470300D03*
Y465300D03*
Y460300D03*
X258375Y495300D03*
X221225D03*
X267600Y582000D03*
Y587000D03*
Y592000D03*
Y597000D03*
X287600D03*
Y592000D03*
Y587000D03*
Y582000D03*
X379088Y537881D03*
Y532881D03*
Y527881D03*
Y522881D03*
X359088D03*
Y527881D03*
Y532881D03*
Y537881D03*
G54D84*
X353864Y606714D03*
Y608683D03*
Y610651D03*
Y612620D03*
Y614589D03*
Y616557D03*
Y618526D03*
X376464D03*
Y616557D03*
Y614589D03*
Y612620D03*
Y610651D03*
Y608683D03*
Y606714D03*
G54D93*
X359258Y623920D03*
X361227D03*
X363195D03*
X365164D03*
X367133D03*
X369101D03*
X371070D03*
Y601320D03*
X369101D03*
X367133D03*
X365164D03*
X363195D03*
X361227D03*
X359258D03*
G54D75*
X350737Y104200D03*
X372770Y52800D03*
Y48200D03*
X372470Y86300D03*
Y81700D03*
G54D57*
X174749Y691815D03*
X363482Y185174D03*
X456088Y54522D03*
X438855Y47144D03*
X438857Y42488D03*
X438846Y51800D03*
X584904Y45967D03*
X609047Y30307D03*
X787000Y29800D03*
X845922Y160314D03*
X854222Y145014D03*
X850306Y340240D03*
X826368Y371019D03*
G54D58*
X197087Y679921D03*
G54D49*
X119400Y642500D03*
X123100D03*
X207900Y641500D03*
X228200Y642700D03*
X215406Y641492D03*
X282600Y685700D03*
X258000Y657300D03*
X297767Y585918D03*
X294167D03*
X336631Y685326D03*
X370650Y193614D03*
X364600Y495500D03*
X849625Y181277D03*
X842984Y374569D03*
X893974Y182735D03*
X890639Y371160D03*
X878439Y404523D03*
G54D94*
X365164Y612620D03*
G54D76*
X353737Y104200D03*
X375770Y52800D03*
Y48200D03*
X375470Y86300D03*
Y81700D03*
G54D85*
X328600Y665850D03*
X324725Y658350D03*
X332475D03*
G54D67*
X244750Y666500D03*
X252250Y662625D03*
Y670375D03*
X244750Y652500D03*
X252250Y656375D03*
Y648625D03*
X361509Y175844D03*
X369009Y171969D03*
Y179719D03*
G54D59*
X211732Y670886D03*
X207795D03*
X203858D03*
X209764Y688956D03*
X205827D03*
X223544Y670886D03*
X219607D03*
X215670D03*
X221575Y688956D03*
X217638D03*
X213701D03*
G54D77*
X356611Y199968D03*
X351611D03*
X346611D03*
X341611D03*
Y219968D03*
X346611D03*
X351611D03*
X356611D03*
G54D95*
X369273Y645871D03*
X360049D03*
Y651827D03*
X369273D03*
G54D68*
X230315Y679921D03*
G54D86*
X372000Y62400D03*
G54D96*
X490835Y47457D03*
G54D69*
X267100Y671900D03*
Y668300D03*
X303100Y661630D03*
Y658030D03*
G54D78*
X297146Y205315D03*
Y202165D03*
Y199016D03*
Y195866D03*
Y192717D03*
X314666Y205315D03*
Y202165D03*
Y199016D03*
Y195866D03*
Y192717D03*
X297146Y277756D03*
Y274606D03*
Y271457D03*
Y268307D03*
Y265158D03*
Y262008D03*
Y258858D03*
Y255709D03*
Y252559D03*
Y249410D03*
Y246260D03*
Y243110D03*
Y239961D03*
Y236811D03*
Y233661D03*
Y230512D03*
Y227362D03*
Y224213D03*
Y221063D03*
Y217913D03*
Y214764D03*
Y211614D03*
Y208465D03*
X314666Y277756D03*
Y274606D03*
Y271457D03*
Y268307D03*
Y265158D03*
Y262008D03*
Y258858D03*
Y255709D03*
Y252559D03*
Y249410D03*
Y246260D03*
Y243110D03*
Y239961D03*
Y236811D03*
Y233661D03*
Y230512D03*
Y227362D03*
Y224213D03*
Y221063D03*
Y217913D03*
Y214764D03*
Y211614D03*
Y208465D03*
X297146Y350197D03*
Y347047D03*
Y343898D03*
Y340748D03*
Y337599D03*
Y334449D03*
Y331299D03*
Y328150D03*
Y325000D03*
Y321850D03*
Y318701D03*
Y315551D03*
Y312402D03*
Y309252D03*
Y306102D03*
Y302953D03*
Y299803D03*
Y296654D03*
Y293504D03*
Y290354D03*
Y287205D03*
Y284055D03*
Y280906D03*
X314666Y350197D03*
Y347047D03*
Y343898D03*
Y340748D03*
Y337599D03*
Y334449D03*
Y331299D03*
Y328150D03*
Y325000D03*
Y321850D03*
Y318701D03*
Y315551D03*
Y312402D03*
Y309252D03*
Y306102D03*
Y302953D03*
Y299803D03*
Y296654D03*
Y293504D03*
Y290354D03*
Y287205D03*
Y284055D03*
Y280906D03*
X297146Y378543D03*
Y375394D03*
Y372244D03*
Y369095D03*
Y365945D03*
Y362795D03*
Y359646D03*
Y356496D03*
Y353347D03*
X314666Y378543D03*
Y375394D03*
Y372244D03*
Y369095D03*
Y365945D03*
Y362795D03*
Y359646D03*
Y356496D03*
Y353347D03*
G54D87*
X421653Y126378D03*
X428740Y121654D03*
X421653Y130709D03*
X428740Y125985D03*
X421653Y136221D03*
X428740Y131496D03*
Y135827D03*
X421653Y183071D03*
Y140551D03*
Y144882D03*
X428740Y140158D03*
X421653Y150394D03*
X428740Y145670D03*
X421653Y154725D03*
X428740Y150000D03*
X421653Y159055D03*
X428740Y154331D03*
X421653Y164567D03*
X428740Y159843D03*
X421653Y168898D03*
X428740Y164173D03*
X421653Y173229D03*
X428740Y168504D03*
X421653Y178740D03*
X428740Y174016D03*
X435827Y126378D03*
X450000D03*
X464173D03*
X442913Y121654D03*
X457086D03*
X471260D03*
X435827Y130709D03*
X442913Y125985D03*
X450000Y130709D03*
X457086Y125985D03*
X464173Y130709D03*
X471260Y125985D03*
X435827Y136221D03*
X442913Y131496D03*
X450000Y136221D03*
X457086Y131496D03*
X464173Y136221D03*
X471260Y131496D03*
X442913Y135827D03*
X457086D03*
X471260D03*
X435827Y183071D03*
X450000D03*
X464173D03*
X435827Y140551D03*
X450000D03*
X464173D03*
X435827Y144882D03*
X442913Y140158D03*
X450000Y144882D03*
X457086Y140158D03*
X464173Y144882D03*
X471260Y140158D03*
X435827Y150394D03*
X442913Y145670D03*
X450000Y150394D03*
X457086Y145670D03*
X464173Y150394D03*
X471260Y145670D03*
X435827Y154725D03*
X442913Y150000D03*
X450000Y154725D03*
X457086Y150000D03*
X464173Y154725D03*
X471260Y150000D03*
X435827Y159055D03*
X442913Y154331D03*
X450000Y159055D03*
X457086Y154331D03*
X464173Y159055D03*
X471260Y154331D03*
X435827Y164567D03*
X442913Y159843D03*
X450000Y164567D03*
X457086Y159843D03*
X464173Y164567D03*
X471260Y159843D03*
X435827Y168898D03*
X442913Y164173D03*
X450000Y168898D03*
X457086Y164173D03*
X464173Y168898D03*
X471260Y164173D03*
X435827Y173229D03*
X442913Y168504D03*
X450000Y173229D03*
X457086Y168504D03*
X464173Y173229D03*
X471260Y168504D03*
X435827Y178740D03*
X442913Y174016D03*
X450000Y178740D03*
X457086Y174016D03*
X464173Y178740D03*
X471260Y174016D03*
X506693Y126378D03*
X520866D03*
X535039D03*
X549212D03*
X513779Y121654D03*
X527953D03*
X542126D03*
X556299D03*
X506693Y130709D03*
X513779Y125985D03*
X520866Y130709D03*
X527953Y125985D03*
X535039Y130709D03*
X542126Y125985D03*
X549212Y130709D03*
X556299Y125985D03*
X506693Y136221D03*
X513779Y131496D03*
X520866Y136221D03*
X527953Y131496D03*
X535039Y136221D03*
X542126Y131496D03*
X549212Y136221D03*
X556299Y131496D03*
X513779Y135827D03*
X527953D03*
X542126D03*
X556299D03*
X506693Y183071D03*
X520866D03*
X535039D03*
X549212D03*
X506693Y140551D03*
X520866D03*
X535039D03*
X549212D03*
X506693Y144882D03*
X513779Y140158D03*
X520866Y144882D03*
X527953Y140158D03*
X535039Y144882D03*
X542126Y140158D03*
X549212Y144882D03*
X556299Y140158D03*
X506693Y150394D03*
X513779Y145670D03*
X520866Y150394D03*
X527953Y145670D03*
X535039Y150394D03*
X542126Y145670D03*
X549212Y150394D03*
X556299Y145670D03*
X506693Y154725D03*
X513779Y150000D03*
X520866Y154725D03*
X527953Y150000D03*
X535039Y154725D03*
X542126Y150000D03*
X549212Y154725D03*
X556299Y150000D03*
X506693Y159055D03*
X513779Y154331D03*
X520866Y159055D03*
X527953Y154331D03*
X535039Y159055D03*
X542126Y154331D03*
X549212Y159055D03*
X556299Y154331D03*
X506693Y164567D03*
X513779Y159843D03*
X520866Y164567D03*
X527953Y159843D03*
X535039Y164567D03*
X542126Y159843D03*
X549212Y164567D03*
X556299Y159843D03*
X506693Y168898D03*
X513779Y164173D03*
X520866Y168898D03*
X527953Y164173D03*
X535039Y168898D03*
X542126Y164173D03*
X549212Y168898D03*
X556299Y164173D03*
X506693Y173229D03*
X513779Y168504D03*
X520866Y173229D03*
X527953Y168504D03*
X535039Y173229D03*
X542126Y168504D03*
X549212Y173229D03*
X556299Y168504D03*
X506693Y178740D03*
X513779Y174016D03*
X520866Y178740D03*
X527953Y174016D03*
X535039Y178740D03*
X542126Y174016D03*
X549212Y178740D03*
X556299Y174016D03*
G54D79*
X351285Y233565D03*
X365125D03*
G54D88*
X391358Y75749D03*
Y69149D03*
X387558D03*
Y75749D03*
G54D97*
X495235Y47457D03*
G54D98*
X461110Y45450D03*
X474890D03*
Y25350D03*
X461110D03*
X603051Y51073D03*
X608957D03*
Y38861D03*
X603051D03*
G54D89*
X372000Y71800D03*
G54D99*
X463079Y45150D03*
X465047D03*
X467016D03*
X468984D03*
X470953D03*
X472921D03*
Y25650D03*
X470953D03*
X468984D03*
X467016D03*
X465047D03*
X463079D03*
M02*
